(kicad_sch
	(version 20250114)
	(generator "eeschema")
	(generator_version "9.0")
	(paper "A3")
	(title_block
		(title "CM4 Baseboard")
		(date "2026-01-05")
		(rev "1.1.1")
		(company "Antmicro Ltd")
		(comment 1 "www.antmicro.com")
	)
	(text " (NFC, CSI, SD, Proximity, ..)"
		(exclude_from_sim no)
		(at 220.98 212.09 0)
		(effects
			(font
				(size 1.27 1.27)
				(thickness 0.254)
				(bold yes)
			)
			(justify left bottom)
		)
	)
	(text "Power requirements & supplies:"
		(exclude_from_sim no)
		(at 15.24 22.86 0)
		(effects
			(font
				(size 2.54 2.54)
				(bold yes)
			)
			(justify left bottom)
		)
	)
	(text "3V3 DCDC (Main)\n"
		(exclude_from_sim no)
		(at 221.615 208.28 0)
		(effects
			(font
				(size 2.5 2.5)
				(bold yes)
			)
			(justify left bottom)
		)
	)
	(text "3V3 DCDC (M.2 NVMe)"
		(exclude_from_sim no)
		(at 221.615 163.83 0)
		(effects
			(font
				(size 2.5 2.5)
				(bold yes)
			)
			(justify left bottom)
		)
	)
	(text "3V3 @ 3A"
		(exclude_from_sim no)
		(at 351.79 173.99 0)
		(effects
			(font
				(size 1.27 1.27)
			)
			(justify left bottom)
		)
	)
	(text "5V @ 6A"
		(exclude_from_sim no)
		(at 358.14 109.22 0)
		(effects
			(font
				(size 1.27 1.27)
			)
			(justify left bottom)
		)
	)
	(text "3V3 @ 3A"
		(exclude_from_sim no)
		(at 351.79 219.71 0)
		(effects
			(font
				(size 1.27 1.27)
			)
			(justify left bottom)
		)
	)
	(text "Primary power - DC Jack input (9-15V)\n"
		(exclude_from_sim no)
		(at 22.86 105.41 0)
		(effects
			(font
				(size 2.54 2.54)
			)
			(justify left bottom)
		)
	)
	(text "Input selector & soft start"
		(exclude_from_sim no)
		(at 13.97 94.615 0)
		(effects
			(font
				(size 2.5 2.5)
				(thickness 0.5)
				(bold yes)
			)
			(justify left bottom)
		)
	)
	(text "3V3 @3A:\n	GPIO conn: 3A (max)\n	CSI: 1.5A (max)\n	LED Strip: 1A (may be switched to 5V)\n	DSI adapter: 0.5A (max)\n	NFC: 350mA+\n	SD card: 100m+?\n	proximity: 50mA/ 1A (max)\n	GPIO expander/levelshifters: 50mA\n3V3-NVMe @3A:\n	M.2: 3A\n3V3 @600mA (from CM4)\n	unused\n1V8 @600mA (from CM4)\n	unused"
		(exclude_from_sim no)
		(at 119.38 81.28 0)
		(effects
			(font
				(size 2.54 2.54)
			)
			(justify left bottom)
		)
	)
	(text "VCC(9-15V, nom. 12V):\n	DCDC 5V: 2.8A\n	DCDC 3V3: 1.1A x2\n5V @6A:\n	CM: 2A(RPi)/3A(PF)\n	GPIO conn.: 3A(max)\n	USB source: 1.5A\n	CSI: 1.5A(max)\n	LED Strip (DNP): 1A\n	DSI adapter: 0.8A(LVDS); 2A(max)\n	HDMI: 50mA+\n"
		(exclude_from_sim no)
		(at 26.67 76.2 0)
		(effects
			(font
				(size 2.54 2.54)
			)
			(justify left bottom)
		)
	)
	(text "5V DCDC"
		(exclude_from_sim no)
		(at 221.615 94.615 0)
		(effects
			(font
				(size 2.5 2.5)
				(bold yes)
			)
			(justify left bottom)
		)
	)
	(junction
		(at 345.44 220.98)
		(diameter 0)
		(color 0 0 0 0)
	)
	(junction
		(at 124.46 121.92)
		(diameter 0)
		(color 0 0 0 0)
	)
	(junction
		(at 321.31 220.98)
		(diameter 0)
		(color 0 0 0 0)
	)
	(junction
		(at 66.04 121.92)
		(diameter 0)
		(color 0 0 0 0)
	)
	(junction
		(at 270.51 220.98)
		(diameter 0)
		(color 0 0 0 0)
	)
	(junction
		(at 370.84 175.26)
		(diameter 0)
		(color 0 0 0 0)
	)
	(junction
		(at 321.31 175.26)
		(diameter 0)
		(color 0 0 0 0)
	)
	(junction
		(at 137.16 134.62)
		(diameter 0)
		(color 0 0 0 0)
	)
	(junction
		(at 85.09 210.82)
		(diameter 0)
		(color 0 0 0 0)
	)
	(junction
		(at 147.32 134.62)
		(diameter 0)
		(color 0 0 0 0)
	)
	(junction
		(at 175.26 121.92)
		(diameter 0)
		(color 0 0 0 0)
	)
	(junction
		(at 137.16 121.92)
		(diameter 0)
		(color 0 0 0 0)
	)
	(junction
		(at 355.6 175.26)
		(diameter 0)
		(color 0 0 0 0)
	)
	(junction
		(at 264.16 110.49)
		(diameter 0)
		(color 0 0 0 0)
	)
	(junction
		(at 271.78 175.26)
		(diameter 0)
		(color 0 0 0 0)
	)
	(junction
		(at 320.04 128.27)
		(diameter 0)
		(color 0 0 0 0)
	)
	(junction
		(at 281.94 110.49)
		(diameter 0)
		(color 0 0 0 0)
	)
	(junction
		(at 334.01 231.14)
		(diameter 0)
		(color 0 0 0 0)
	)
	(junction
		(at 49.53 210.82)
		(diameter 0)
		(color 0 0 0 0)
	)
	(junction
		(at 109.22 166.37)
		(diameter 0)
		(color 0 0 0 0)
	)
	(junction
		(at 163.83 121.92)
		(diameter 0)
		(color 0 0 0 0)
	)
	(junction
		(at 335.28 110.49)
		(diameter 0)
		(color 0 0 0 0)
	)
	(junction
		(at 62.23 210.82)
		(diameter 0)
		(color 0 0 0 0)
	)
	(junction
		(at 320.04 110.49)
		(diameter 0)
		(color 0 0 0 0)
	)
	(junction
		(at 388.62 220.98)
		(diameter 0)
		(color 0 0 0 0)
	)
	(junction
		(at 345.44 110.49)
		(diameter 0)
		(color 0 0 0 0)
	)
	(junction
		(at 355.6 220.98)
		(diameter 0)
		(color 0 0 0 0)
	)
	(junction
		(at 97.79 121.92)
		(diameter 0)
		(color 0 0 0 0)
	)
	(junction
		(at 372.11 220.98)
		(diameter 0)
		(color 0 0 0 0)
	)
	(junction
		(at 260.35 110.49)
		(diameter 0)
		(color 0 0 0 0)
	)
	(junction
		(at 87.63 229.87)
		(diameter 0)
		(color 0 0 0 0)
	)
	(junction
		(at 373.38 110.49)
		(diameter 0)
		(color 0 0 0 0)
	)
	(junction
		(at 171.45 121.92)
		(diameter 0)
		(color 0 0 0 0)
	)
	(junction
		(at 363.22 110.49)
		(diameter 0)
		(color 0 0 0 0)
	)
	(junction
		(at 66.04 210.82)
		(diameter 0)
		(color 0 0 0 0)
	)
	(junction
		(at 185.42 121.92)
		(diameter 0)
		(color 0 0 0 0)
	)
	(junction
		(at 388.62 177.8)
		(diameter 0)
		(color 0 0 0 0)
	)
	(junction
		(at 43.18 121.92)
		(diameter 0)
		(color 0 0 0 0)
	)
	(junction
		(at 335.28 123.19)
		(diameter 0)
		(color 0 0 0 0)
	)
	(junction
		(at 279.4 220.98)
		(diameter 0)
		(color 0 0 0 0)
	)
	(junction
		(at 354.33 110.49)
		(diameter 0)
		(color 0 0 0 0)
	)
	(junction
		(at 281.94 123.19)
		(diameter 0)
		(color 0 0 0 0)
	)
	(junction
		(at 85.09 166.37)
		(diameter 0)
		(color 0 0 0 0)
	)
	(junction
		(at 85.09 121.92)
		(diameter 0)
		(color 0 0 0 0)
	)
	(junction
		(at 273.05 110.49)
		(diameter 0)
		(color 0 0 0 0)
	)
	(junction
		(at 289.56 134.62)
		(diameter 0)
		(color 0 0 0 0)
	)
	(junction
		(at 279.4 226.06)
		(diameter 0)
		(color 0 0 0 0)
	)
	(junction
		(at 59.69 121.92)
		(diameter 0)
		(color 0 0 0 0)
	)
	(junction
		(at 109.22 121.92)
		(diameter 0)
		(color 0 0 0 0)
	)
	(junction
		(at 87.63 140.97)
		(diameter 0)
		(color 0 0 0 0)
	)
	(junction
		(at 334.01 220.98)
		(diameter 0)
		(color 0 0 0 0)
	)
	(junction
		(at 334.01 185.42)
		(diameter 0)
		(color 0 0 0 0)
	)
	(junction
		(at 36.83 127)
		(diameter 0)
		(color 0 0 0 0)
	)
	(junction
		(at 285.75 180.34)
		(diameter 0)
		(color 0 0 0 0)
	)
	(junction
		(at 388.62 115.57)
		(diameter 0)
		(color 0 0 0 0)
	)
	(junction
		(at 66.04 166.37)
		(diameter 0)
		(color 0 0 0 0)
	)
	(junction
		(at 334.01 175.26)
		(diameter 0)
		(color 0 0 0 0)
	)
	(junction
		(at 87.63 185.42)
		(diameter 0)
		(color 0 0 0 0)
	)
	(junction
		(at 345.44 175.26)
		(diameter 0)
		(color 0 0 0 0)
	)
	(no_connect
		(at 294.64 130.81)
	)
	(no_connect
		(at 294.64 128.27)
	)
	(no_connect
		(at 294.64 133.35)
	)
	(wire
		(pts
			(xy 311.15 185.42) (xy 334.01 185.42)
		)
		(stroke
			(width 0)
			(type default)
		)
	)
	(wire
		(pts
			(xy 367.03 220.98) (xy 372.11 220.98)
		)
		(stroke
			(width 0)
			(type default)
		)
	)
	(wire
		(pts
			(xy 355.6 186.69) (xy 355.6 194.31)
		)
		(stroke
			(width 0)
			(type default)
		)
	)
	(polyline
		(pts
			(xy 219.71 157.48) (xy 407.67 157.48)
		)
		(stroke
			(width 0)
			(type default)
		)
	)
	(wire
		(pts
			(xy 85.09 182.88) (xy 85.09 166.37)
		)
		(stroke
			(width 0)
			(type default)
		)
	)
	(wire
		(pts
			(xy 66.04 229.87) (xy 66.04 232.41)
		)
		(stroke
			(width 0)
			(type default)
		)
	)
	(wire
		(pts
			(xy 334.01 185.42) (xy 334.01 187.96)
		)
		(stroke
			(width 0)
			(type default)
		)
	)
	(wire
		(pts
			(xy 137.16 121.92) (xy 144.78 121.92)
		)
		(stroke
			(width 0)
			(type default)
		)
	)
	(wire
		(pts
			(xy 321.31 180.34) (xy 321.31 175.26)
		)
		(stroke
			(width 0)
			(type default)
		)
	)
	(wire
		(pts
			(xy 59.69 121.92) (xy 66.04 121.92)
		)
		(stroke
			(width 0)
			(type default)
		)
	)
	(wire
		(pts
			(xy 335.28 121.92) (xy 335.28 123.19)
		)
		(stroke
			(width 0)
			(type default)
		)
	)
	(wire
		(pts
			(xy 381 107.95) (xy 381 110.49)
		)
		(stroke
			(width 0)
			(type default)
		)
	)
	(wire
		(pts
			(xy 317.5 123.19) (xy 335.28 123.19)
		)
		(stroke
			(width 0)
			(type default)
		)
	)
	(wire
		(pts
			(xy 363.22 113.03) (xy 363.22 110.49)
		)
		(stroke
			(width 0)
			(type default)
		)
	)
	(wire
		(pts
			(xy 83.82 182.88) (xy 85.09 182.88)
		)
		(stroke
			(width 0)
			(type default)
		)
	)
	(wire
		(pts
			(xy 270.51 232.41) (xy 270.51 234.95)
		)
		(stroke
			(width 0)
			(type default)
		)
	)
	(wire
		(pts
			(xy 361.95 175.26) (xy 355.6 175.26)
		)
		(stroke
			(width 0)
			(type default)
		)
	)
	(wire
		(pts
			(xy 335.28 129.54) (xy 335.28 137.16)
		)
		(stroke
			(width 0)
			(type default)
		)
	)
	(wire
		(pts
			(xy 109.22 121.92) (xy 124.46 121.92)
		)
		(stroke
			(width 0)
			(type default)
		)
	)
	(wire
		(pts
			(xy 36.83 124.46) (xy 36.83 127)
		)
		(stroke
			(width 0)
			(type default)
		)
	)
	(wire
		(pts
			(xy 345.44 110.49) (xy 354.33 110.49)
		)
		(stroke
			(width 0)
			(type default)
		)
	)
	(wire
		(pts
			(xy 87.63 130.81) (xy 87.63 140.97)
		)
		(stroke
			(width 0)
			(type default)
		)
	)
	(wire
		(pts
			(xy 320.04 110.49) (xy 327.66 110.49)
		)
		(stroke
			(width 0)
			(type default)
		)
	)
	(wire
		(pts
			(xy 62.23 210.82) (xy 66.04 210.82)
		)
		(stroke
			(width 0)
			(type default)
		)
	)
	(wire
		(pts
			(xy 321.31 220.98) (xy 311.15 220.98)
		)
		(stroke
			(width 0)
			(type default)
		)
	)
	(wire
		(pts
			(xy 323.85 129.54) (xy 323.85 128.27)
		)
		(stroke
			(width 0)
			(type default)
		)
	)
	(wire
		(pts
			(xy 78.74 219.71) (xy 87.63 219.71)
		)
		(stroke
			(width 0)
			(type default)
		)
	)
	(wire
		(pts
			(xy 372.11 218.44) (xy 372.11 220.98)
		)
		(stroke
			(width 0)
			(type default)
		)
	)
	(wire
		(pts
			(xy 334.01 182.88) (xy 334.01 185.42)
		)
		(stroke
			(width 0)
			(type default)
		)
	)
	(wire
		(pts
			(xy 318.77 226.06) (xy 321.31 226.06)
		)
		(stroke
			(width 0)
			(type default)
		)
	)
	(wire
		(pts
			(xy 273.05 113.03) (xy 273.05 110.49)
		)
		(stroke
			(width 0)
			(type default)
		)
	)
	(wire
		(pts
			(xy 85.09 210.82) (xy 109.22 210.82)
		)
		(stroke
			(width 0)
			(type default)
		)
	)
	(wire
		(pts
			(xy 321.31 175.26) (xy 311.15 175.26)
		)
		(stroke
			(width 0)
			(type default)
		)
	)
	(wire
		(pts
			(xy 260.35 119.38) (xy 260.35 118.11)
		)
		(stroke
			(width 0)
			(type default)
		)
	)
	(wire
		(pts
			(xy 345.44 175.26) (xy 355.6 175.26)
		)
		(stroke
			(width 0)
			(type default)
		)
	)
	(wire
		(pts
			(xy 154.94 121.92) (xy 163.83 121.92)
		)
		(stroke
			(width 0)
			(type default)
		)
	)
	(wire
		(pts
			(xy 370.84 173.99) (xy 370.84 175.26)
		)
		(stroke
			(width 0)
			(type default)
		)
	)
	(wire
		(pts
			(xy 271.78 186.69) (xy 271.78 194.31)
		)
		(stroke
			(width 0)
			(type default)
		)
	)
	(wire
		(pts
			(xy 83.82 227.33) (xy 85.09 227.33)
		)
		(stroke
			(width 0)
			(type default)
		)
	)
	(wire
		(pts
			(xy 66.04 227.33) (xy 66.04 210.82)
		)
		(stroke
			(width 0)
			(type default)
		)
	)
	(wire
		(pts
			(xy 43.18 121.92) (xy 59.69 121.92)
		)
		(stroke
			(width 0)
			(type default)
		)
	)
	(wire
		(pts
			(xy 289.56 142.24) (xy 320.04 142.24)
		)
		(stroke
			(width 0)
			(type default)
		)
	)
	(wire
		(pts
			(xy 43.18 129.54) (xy 43.18 130.81)
		)
		(stroke
			(width 0)
			(type default)
		)
	)
	(wire
		(pts
			(xy 49.53 210.82) (xy 62.23 210.82)
		)
		(stroke
			(width 0)
			(type default)
		)
	)
	(wire
		(pts
			(xy 33.02 121.92) (xy 43.18 121.92)
		)
		(stroke
			(width 0)
			(type default)
		)
	)
	(wire
		(pts
			(xy 370.84 175.26) (xy 367.03 175.26)
		)
		(stroke
			(width 0)
			(type default)
		)
	)
	(wire
		(pts
			(xy 66.04 121.92) (xy 71.12 121.92)
		)
		(stroke
			(width 0)
			(type default)
		)
	)
	(wire
		(pts
			(xy 124.46 121.92) (xy 124.46 124.46)
		)
		(stroke
			(width 0)
			(type default)
		)
	)
	(wire
		(pts
			(xy 273.05 110.49) (xy 281.94 110.49)
		)
		(stroke
			(width 0)
			(type default)
		)
	)
	(polyline
		(pts
			(xy 219.71 245.11) (xy 219.71 87.63)
		)
		(stroke
			(width 0)
			(type default)
		)
	)
	(wire
		(pts
			(xy 281.94 123.19) (xy 281.94 124.46)
		)
		(stroke
			(width 0)
			(type default)
		)
	)
	(wire
		(pts
			(xy 87.63 185.42) (xy 87.63 187.96)
		)
		(stroke
			(width 0)
			(type default)
		)
	)
	(wire
		(pts
			(xy 78.74 175.26) (xy 87.63 175.26)
		)
		(stroke
			(width 0)
			(type default)
		)
	)
	(wire
		(pts
			(xy 109.22 166.37) (xy 109.22 210.82)
		)
		(stroke
			(width 0)
			(type default)
		)
	)
	(wire
		(pts
			(xy 388.62 233.68) (xy 388.62 236.22)
		)
		(stroke
			(width 0)
			(type default)
		)
	)
	(wire
		(pts
			(xy 33.02 127) (xy 36.83 127)
		)
		(stroke
			(width 0)
			(type default)
		)
	)
	(wire
		(pts
			(xy 332.74 110.49) (xy 335.28 110.49)
		)
		(stroke
			(width 0)
			(type default)
		)
	)
	(wire
		(pts
			(xy 147.32 134.62) (xy 147.32 137.16)
		)
		(stroke
			(width 0)
			(type default)
		)
	)
	(wire
		(pts
			(xy 66.04 111.76) (xy 66.04 121.92)
		)
		(stroke
			(width 0)
			(type default)
		)
	)
	(wire
		(pts
			(xy 270.51 220.98) (xy 279.4 220.98)
		)
		(stroke
			(width 0)
			(type default)
		)
	)
	(wire
		(pts
			(xy 334.01 220.98) (xy 345.44 220.98)
		)
		(stroke
			(width 0)
			(type default)
		)
	)
	(polyline
		(pts
			(xy 219.71 245.11) (xy 219.71 284.48)
		)
		(stroke
			(width 0)
			(type default)
		)
	)
	(wire
		(pts
			(xy 279.4 220.98) (xy 290.83 220.98)
		)
		(stroke
			(width 0)
			(type default)
		)
	)
	(wire
		(pts
			(xy 67.31 185.42) (xy 66.04 185.42)
		)
		(stroke
			(width 0)
			(type default)
		)
	)
	(wire
		(pts
			(xy 147.32 134.62) (xy 163.83 134.62)
		)
		(stroke
			(width 0)
			(type default)
		)
	)
	(wire
		(pts
			(xy 321.31 220.98) (xy 323.85 220.98)
		)
		(stroke
			(width 0)
			(type default)
		)
	)
	(wire
		(pts
			(xy 271.78 175.26) (xy 271.78 181.61)
		)
		(stroke
			(width 0)
			(type default)
		)
	)
	(wire
		(pts
			(xy 345.44 119.38) (xy 345.44 118.11)
		)
		(stroke
			(width 0)
			(type default)
		)
	)
	(wire
		(pts
			(xy 66.04 140.97) (xy 66.04 143.51)
		)
		(stroke
			(width 0)
			(type default)
		)
	)
	(wire
		(pts
			(xy 389.89 220.98) (xy 388.62 220.98)
		)
		(stroke
			(width 0)
			(type default)
		)
	)
	(wire
		(pts
			(xy 66.04 148.59) (xy 66.04 149.86)
		)
		(stroke
			(width 0)
			(type default)
		)
	)
	(wire
		(pts
			(xy 109.22 121.92) (xy 109.22 166.37)
		)
		(stroke
			(width 0)
			(type default)
		)
	)
	(wire
		(pts
			(xy 354.33 119.38) (xy 354.33 118.11)
		)
		(stroke
			(width 0)
			(type default)
		)
	)
	(wire
		(pts
			(xy 335.28 123.19) (xy 335.28 124.46)
		)
		(stroke
			(width 0)
			(type default)
		)
	)
	(wire
		(pts
			(xy 279.4 234.95) (xy 279.4 232.41)
		)
		(stroke
			(width 0)
			(type default)
		)
	)
	(wire
		(pts
			(xy 59.69 120.65) (xy 59.69 121.92)
		)
		(stroke
			(width 0)
			(type default)
		)
	)
	(wire
		(pts
			(xy 289.56 234.95) (xy 289.56 231.14)
		)
		(stroke
			(width 0)
			(type default)
		)
	)
	(wire
		(pts
			(xy 264.16 110.49) (xy 273.05 110.49)
		)
		(stroke
			(width 0)
			(type default)
		)
	)
	(wire
		(pts
			(xy 78.74 128.27) (xy 78.74 130.81)
		)
		(stroke
			(width 0)
			(type default)
		)
	)
	(wire
		(pts
			(xy 264.16 119.38) (xy 264.16 118.11)
		)
		(stroke
			(width 0)
			(type default)
		)
	)
	(wire
		(pts
			(xy 334.01 220.98) (xy 334.01 223.52)
		)
		(stroke
			(width 0)
			(type default)
		)
	)
	(wire
		(pts
			(xy 293.37 137.16) (xy 293.37 135.89)
		)
		(stroke
			(width 0)
			(type default)
		)
	)
	(wire
		(pts
			(xy 334.01 231.14) (xy 334.01 232.41)
		)
		(stroke
			(width 0)
			(type default)
		)
	)
	(wire
		(pts
			(xy 67.31 140.97) (xy 66.04 140.97)
		)
		(stroke
			(width 0)
			(type default)
		)
	)
	(wire
		(pts
			(xy 388.62 116.84) (xy 388.62 115.57)
		)
		(stroke
			(width 0)
			(type default)
		)
	)
	(wire
		(pts
			(xy 137.16 121.92) (xy 137.16 124.46)
		)
		(stroke
			(width 0)
			(type default)
		)
	)
	(wire
		(pts
			(xy 363.22 110.49) (xy 367.03 110.49)
		)
		(stroke
			(width 0)
			(type default)
		)
	)
	(wire
		(pts
			(xy 67.31 227.33) (xy 66.04 227.33)
		)
		(stroke
			(width 0)
			(type default)
		)
	)
	(wire
		(pts
			(xy 381 220.98) (xy 372.11 220.98)
		)
		(stroke
			(width 0)
			(type default)
		)
	)
	(wire
		(pts
			(xy 345.44 220.98) (xy 355.6 220.98)
		)
		(stroke
			(width 0)
			(type default)
		)
	)
	(wire
		(pts
			(xy 311.15 226.06) (xy 313.69 226.06)
		)
		(stroke
			(width 0)
			(type default)
		)
	)
	(wire
		(pts
			(xy 185.42 121.92) (xy 185.42 130.81)
		)
		(stroke
			(width 0)
			(type default)
		)
	)
	(wire
		(pts
			(xy 109.22 120.65) (xy 109.22 121.92)
		)
		(stroke
			(width 0)
			(type default)
		)
	)
	(wire
		(pts
			(xy 389.89 115.57) (xy 388.62 115.57)
		)
		(stroke
			(width 0)
			(type default)
		)
	)
	(wire
		(pts
			(xy 87.63 148.59) (xy 87.63 149.86)
		)
		(stroke
			(width 0)
			(type default)
		)
	)
	(wire
		(pts
			(xy 334.01 175.26) (xy 345.44 175.26)
		)
		(stroke
			(width 0)
			(type default)
		)
	)
	(wire
		(pts
			(xy 355.6 232.41) (xy 355.6 238.76)
		)
		(stroke
			(width 0)
			(type default)
		)
	)
	(wire
		(pts
			(xy 85.09 166.37) (xy 109.22 166.37)
		)
		(stroke
			(width 0)
			(type default)
		)
	)
	(wire
		(pts
			(xy 81.28 210.82) (xy 85.09 210.82)
		)
		(stroke
			(width 0)
			(type default)
		)
	)
	(wire
		(pts
			(xy 388.62 190.5) (xy 388.62 193.04)
		)
		(stroke
			(width 0)
			(type default)
		)
	)
	(wire
		(pts
			(xy 175.26 129.54) (xy 175.26 134.62)
		)
		(stroke
			(width 0)
			(type default)
		)
	)
	(wire
		(pts
			(xy 335.28 116.84) (xy 335.28 110.49)
		)
		(stroke
			(width 0)
			(type default)
		)
	)
	(wire
		(pts
			(xy 171.45 121.92) (xy 175.26 121.92)
		)
		(stroke
			(width 0)
			(type default)
		)
	)
	(wire
		(pts
			(xy 388.62 173.99) (xy 388.62 177.8)
		)
		(stroke
			(width 0)
			(type default)
		)
	)
	(wire
		(pts
			(xy 311.15 231.14) (xy 334.01 231.14)
		)
		(stroke
			(width 0)
			(type default)
		)
	)
	(wire
		(pts
			(xy 81.28 121.92) (xy 85.09 121.92)
		)
		(stroke
			(width 0)
			(type default)
		)
	)
	(wire
		(pts
			(xy 321.31 226.06) (xy 321.31 220.98)
		)
		(stroke
			(width 0)
			(type default)
		)
	)
	(wire
		(pts
			(xy 163.83 121.92) (xy 163.83 124.46)
		)
		(stroke
			(width 0)
			(type default)
		)
	)
	(wire
		(pts
			(xy 381 218.44) (xy 381 220.98)
		)
		(stroke
			(width 0)
			(type default)
		)
	)
	(wire
		(pts
			(xy 345.44 175.26) (xy 345.44 181.61)
		)
		(stroke
			(width 0)
			(type default)
		)
	)
	(wire
		(pts
			(xy 328.93 175.26) (xy 334.01 175.26)
		)
		(stroke
			(width 0)
			(type default)
		)
	)
	(wire
		(pts
			(xy 289.56 125.73) (xy 294.64 125.73)
		)
		(stroke
			(width 0)
			(type default)
		)
	)
	(wire
		(pts
			(xy 289.56 194.31) (xy 289.56 185.42)
		)
		(stroke
			(width 0)
			(type default)
		)
	)
	(wire
		(pts
			(xy 281.94 110.49) (xy 294.64 110.49)
		)
		(stroke
			(width 0)
			(type default)
		)
	)
	(wire
		(pts
			(xy 163.83 121.92) (xy 171.45 121.92)
		)
		(stroke
			(width 0)
			(type default)
		)
	)
	(wire
		(pts
			(xy 124.46 134.62) (xy 137.16 134.62)
		)
		(stroke
			(width 0)
			(type default)
		)
	)
	(wire
		(pts
			(xy 137.16 110.49) (xy 147.32 110.49)
		)
		(stroke
			(width 0)
			(type default)
		)
	)
	(wire
		(pts
			(xy 311.15 180.34) (xy 313.69 180.34)
		)
		(stroke
			(width 0)
			(type default)
		)
	)
	(wire
		(pts
			(xy 271.78 175.26) (xy 290.83 175.26)
		)
		(stroke
			(width 0)
			(type default)
		)
	)
	(wire
		(pts
			(xy 283.21 180.34) (xy 285.75 180.34)
		)
		(stroke
			(width 0)
			(type default)
		)
	)
	(wire
		(pts
			(xy 289.56 231.14) (xy 290.83 231.14)
		)
		(stroke
			(width 0)
			(type default)
		)
	)
	(wire
		(pts
			(xy 175.26 121.92) (xy 185.42 121.92)
		)
		(stroke
			(width 0)
			(type default)
		)
	)
	(wire
		(pts
			(xy 83.82 185.42) (xy 87.63 185.42)
		)
		(stroke
			(width 0)
			(type default)
		)
	)
	(wire
		(pts
			(xy 281.94 113.03) (xy 281.94 110.49)
		)
		(stroke
			(width 0)
			(type default)
		)
	)
	(wire
		(pts
			(xy 388.62 179.07) (xy 388.62 177.8)
		)
		(stroke
			(width 0)
			(type default)
		)
	)
	(wire
		(pts
			(xy 185.42 144.78) (xy 185.42 135.89)
		)
		(stroke
			(width 0)
			(type default)
		)
	)
	(wire
		(pts
			(xy 87.63 237.49) (xy 87.63 238.76)
		)
		(stroke
			(width 0)
			(type default)
		)
	)
	(wire
		(pts
			(xy 345.44 220.98) (xy 345.44 227.33)
		)
		(stroke
			(width 0)
			(type default)
		)
	)
	(wire
		(pts
			(xy 260.35 113.03) (xy 260.35 110.49)
		)
		(stroke
			(width 0)
			(type default)
		)
	)
	(wire
		(pts
			(xy 318.77 137.16) (xy 318.77 135.89)
		)
		(stroke
			(width 0)
			(type default)
		)
	)
	(wire
		(pts
			(xy 152.4 110.49) (xy 163.83 110.49)
		)
		(stroke
			(width 0)
			(type default)
		)
	)
	(wire
		(pts
			(xy 33.02 124.46) (xy 36.83 124.46)
		)
		(stroke
			(width 0)
			(type default)
		)
	)
	(wire
		(pts
			(xy 185.42 119.38) (xy 185.42 121.92)
		)
		(stroke
			(width 0)
			(type default)
		)
	)
	(wire
		(pts
			(xy 78.74 217.17) (xy 78.74 219.71)
		)
		(stroke
			(width 0)
			(type default)
		)
	)
	(wire
		(pts
			(xy 388.62 222.25) (xy 388.62 220.98)
		)
		(stroke
			(width 0)
			(type default)
		)
	)
	(wire
		(pts
			(xy 83.82 138.43) (xy 85.09 138.43)
		)
		(stroke
			(width 0)
			(type default)
		)
	)
	(polyline
		(pts
			(xy 407.67 158.75) (xy 407.67 157.48)
		)
		(stroke
			(width 0)
			(type default)
		)
	)
	(wire
		(pts
			(xy 85.09 121.92) (xy 97.79 121.92)
		)
		(stroke
			(width 0)
			(type default)
		)
	)
	(wire
		(pts
			(xy 78.74 130.81) (xy 87.63 130.81)
		)
		(stroke
			(width 0)
			(type default)
		)
	)
	(wire
		(pts
			(xy 260.35 110.49) (xy 264.16 110.49)
		)
		(stroke
			(width 0)
			(type default)
		)
	)
	(wire
		(pts
			(xy 256.54 110.49) (xy 260.35 110.49)
		)
		(stroke
			(width 0)
			(type default)
		)
	)
	(wire
		(pts
			(xy 87.63 229.87) (xy 87.63 232.41)
		)
		(stroke
			(width 0)
			(type default)
		)
	)
	(wire
		(pts
			(xy 78.74 172.72) (xy 78.74 175.26)
		)
		(stroke
			(width 0)
			(type default)
		)
	)
	(wire
		(pts
			(xy 87.63 193.04) (xy 87.63 194.31)
		)
		(stroke
			(width 0)
			(type default)
		)
	)
	(wire
		(pts
			(xy 334.01 175.26) (xy 334.01 177.8)
		)
		(stroke
			(width 0)
			(type default)
		)
	)
	(wire
		(pts
			(xy 354.33 113.03) (xy 354.33 110.49)
		)
		(stroke
			(width 0)
			(type default)
		)
	)
	(wire
		(pts
			(xy 321.31 175.26) (xy 323.85 175.26)
		)
		(stroke
			(width 0)
			(type default)
		)
	)
	(wire
		(pts
			(xy 289.56 140.97) (xy 289.56 142.24)
		)
		(stroke
			(width 0)
			(type default)
		)
	)
	(wire
		(pts
			(xy 163.83 129.54) (xy 163.83 134.62)
		)
		(stroke
			(width 0)
			(type default)
		)
	)
	(wire
		(pts
			(xy 289.56 125.73) (xy 289.56 134.62)
		)
		(stroke
			(width 0)
			(type default)
		)
	)
	(wire
		(pts
			(xy 318.77 135.89) (xy 317.5 135.89)
		)
		(stroke
			(width 0)
			(type default)
		)
	)
	(wire
		(pts
			(xy 285.75 180.34) (xy 290.83 180.34)
		)
		(stroke
			(width 0)
			(type default)
		)
	)
	(wire
		(pts
			(xy 335.28 110.49) (xy 345.44 110.49)
		)
		(stroke
			(width 0)
			(type default)
		)
	)
	(wire
		(pts
			(xy 373.38 107.95) (xy 373.38 110.49)
		)
		(stroke
			(width 0)
			(type default)
		)
	)
	(wire
		(pts
			(xy 67.31 182.88) (xy 66.04 182.88)
		)
		(stroke
			(width 0)
			(type default)
		)
	)
	(wire
		(pts
			(xy 289.56 135.89) (xy 289.56 134.62)
		)
		(stroke
			(width 0)
			(type default)
		)
	)
	(wire
		(pts
			(xy 361.95 220.98) (xy 355.6 220.98)
		)
		(stroke
			(width 0)
			(type default)
		)
	)
	(wire
		(pts
			(xy 87.63 219.71) (xy 87.63 229.87)
		)
		(stroke
			(width 0)
			(type default)
		)
	)
	(wire
		(pts
			(xy 293.37 135.89) (xy 294.64 135.89)
		)
		(stroke
			(width 0)
			(type default)
		)
	)
	(wire
		(pts
			(xy 328.93 220.98) (xy 334.01 220.98)
		)
		(stroke
			(width 0)
			(type default)
		)
	)
	(wire
		(pts
			(xy 345.44 232.41) (xy 345.44 238.76)
		)
		(stroke
			(width 0)
			(type default)
		)
	)
	(wire
		(pts
			(xy 388.62 115.57) (xy 388.62 114.3)
		)
		(stroke
			(width 0)
			(type default)
		)
	)
	(wire
		(pts
			(xy 85.09 138.43) (xy 85.09 121.92)
		)
		(stroke
			(width 0)
			(type default)
		)
	)
	(wire
		(pts
			(xy 83.82 229.87) (xy 87.63 229.87)
		)
		(stroke
			(width 0)
			(type default)
		)
	)
	(wire
		(pts
			(xy 372.11 175.26) (xy 370.84 175.26)
		)
		(stroke
			(width 0)
			(type default)
		)
	)
	(wire
		(pts
			(xy 270.51 220.98) (xy 270.51 227.33)
		)
		(stroke
			(width 0)
			(type default)
		)
	)
	(wire
		(pts
			(xy 388.62 128.27) (xy 388.62 130.81)
		)
		(stroke
			(width 0)
			(type default)
		)
	)
	(wire
		(pts
			(xy 261.62 220.98) (xy 270.51 220.98)
		)
		(stroke
			(width 0)
			(type default)
		)
	)
	(wire
		(pts
			(xy 66.04 237.49) (xy 66.04 238.76)
		)
		(stroke
			(width 0)
			(type default)
		)
	)
	(wire
		(pts
			(xy 67.31 138.43) (xy 66.04 138.43)
		)
		(stroke
			(width 0)
			(type default)
		)
	)
	(wire
		(pts
			(xy 147.32 142.24) (xy 147.32 144.78)
		)
		(stroke
			(width 0)
			(type default)
		)
	)
	(wire
		(pts
			(xy 281.94 123.19) (xy 281.94 118.11)
		)
		(stroke
			(width 0)
			(type default)
		)
	)
	(wire
		(pts
			(xy 363.22 119.38) (xy 363.22 118.11)
		)
		(stroke
			(width 0)
			(type default)
		)
	)
	(wire
		(pts
			(xy 389.89 177.8) (xy 388.62 177.8)
		)
		(stroke
			(width 0)
			(type default)
		)
	)
	(wire
		(pts
			(xy 97.79 121.92) (xy 109.22 121.92)
		)
		(stroke
			(width 0)
			(type default)
		)
	)
	(wire
		(pts
			(xy 124.46 129.54) (xy 124.46 134.62)
		)
		(stroke
			(width 0)
			(type default)
		)
	)
	(wire
		(pts
			(xy 73.66 111.76) (xy 66.04 111.76)
		)
		(stroke
			(width 0)
			(type default)
		)
	)
	(wire
		(pts
			(xy 372.11 110.49) (xy 373.38 110.49)
		)
		(stroke
			(width 0)
			(type default)
		)
	)
	(wire
		(pts
			(xy 175.26 121.92) (xy 175.26 124.46)
		)
		(stroke
			(width 0)
			(type default)
		)
	)
	(wire
		(pts
			(xy 264.16 113.03) (xy 264.16 110.49)
		)
		(stroke
			(width 0)
			(type default)
		)
	)
	(wire
		(pts
			(xy 66.04 193.04) (xy 66.04 194.31)
		)
		(stroke
			(width 0)
			(type default)
		)
	)
	(wire
		(pts
			(xy 354.33 110.49) (xy 363.22 110.49)
		)
		(stroke
			(width 0)
			(type default)
		)
	)
	(wire
		(pts
			(xy 320.04 128.27) (xy 320.04 142.24)
		)
		(stroke
			(width 0)
			(type default)
		)
	)
	(wire
		(pts
			(xy 81.28 166.37) (xy 85.09 166.37)
		)
		(stroke
			(width 0)
			(type default)
		)
	)
	(wire
		(pts
			(xy 66.04 210.82) (xy 71.12 210.82)
		)
		(stroke
			(width 0)
			(type default)
		)
	)
	(wire
		(pts
			(xy 66.04 166.37) (xy 71.12 166.37)
		)
		(stroke
			(width 0)
			(type default)
		)
	)
	(wire
		(pts
			(xy 334.01 237.49) (xy 334.01 238.76)
		)
		(stroke
			(width 0)
			(type default)
		)
	)
	(wire
		(pts
			(xy 261.62 175.26) (xy 271.78 175.26)
		)
		(stroke
			(width 0)
			(type default)
		)
	)
	(polyline
		(pts
			(xy 12.7 87.63) (xy 407.67 87.63)
		)
		(stroke
			(width 0)
			(type default)
		)
	)
	(wire
		(pts
			(xy 46.99 210.82) (xy 49.53 210.82)
		)
		(stroke
			(width 0)
			(type default)
		)
	)
	(wire
		(pts
			(xy 185.42 121.92) (xy 187.96 121.92)
		)
		(stroke
			(width 0)
			(type default)
		)
	)
	(wire
		(pts
			(xy 373.38 110.49) (xy 381 110.49)
		)
		(stroke
			(width 0)
			(type default)
		)
	)
	(wire
		(pts
			(xy 83.82 140.97) (xy 87.63 140.97)
		)
		(stroke
			(width 0)
			(type default)
		)
	)
	(wire
		(pts
			(xy 147.32 128.27) (xy 147.32 134.62)
		)
		(stroke
			(width 0)
			(type default)
		)
	)
	(wire
		(pts
			(xy 163.83 110.49) (xy 163.83 121.92)
		)
		(stroke
			(width 0)
			(type default)
		)
	)
	(wire
		(pts
			(xy 281.94 130.81) (xy 281.94 129.54)
		)
		(stroke
			(width 0)
			(type default)
		)
	)
	(wire
		(pts
			(xy 66.04 138.43) (xy 66.04 121.92)
		)
		(stroke
			(width 0)
			(type default)
		)
	)
	(wire
		(pts
			(xy 36.83 127) (xy 36.83 130.81)
		)
		(stroke
			(width 0)
			(type default)
		)
	)
	(wire
		(pts
			(xy 320.04 110.49) (xy 320.04 111.76)
		)
		(stroke
			(width 0)
			(type default)
		)
	)
	(wire
		(pts
			(xy 97.79 120.65) (xy 97.79 121.92)
		)
		(stroke
			(width 0)
			(type default)
		)
	)
	(wire
		(pts
			(xy 273.05 119.38) (xy 273.05 118.11)
		)
		(stroke
			(width 0)
			(type default)
		)
	)
	(wire
		(pts
			(xy 355.6 175.26) (xy 355.6 181.61)
		)
		(stroke
			(width 0)
			(type default)
		)
	)
	(wire
		(pts
			(xy 320.04 128.27) (xy 323.85 128.27)
		)
		(stroke
			(width 0)
			(type default)
		)
	)
	(wire
		(pts
			(xy 355.6 220.98) (xy 355.6 227.33)
		)
		(stroke
			(width 0)
			(type default)
		)
	)
	(wire
		(pts
			(xy 85.09 227.33) (xy 85.09 210.82)
		)
		(stroke
			(width 0)
			(type default)
		)
	)
	(wire
		(pts
			(xy 87.63 175.26) (xy 87.63 185.42)
		)
		(stroke
			(width 0)
			(type default)
		)
	)
	(wire
		(pts
			(xy 66.04 182.88) (xy 66.04 166.37)
		)
		(stroke
			(width 0)
			(type default)
		)
	)
	(wire
		(pts
			(xy 345.44 186.69) (xy 345.44 194.31)
		)
		(stroke
			(width 0)
			(type default)
		)
	)
	(wire
		(pts
			(xy 317.5 128.27) (xy 320.04 128.27)
		)
		(stroke
			(width 0)
			(type default)
		)
	)
	(wire
		(pts
			(xy 124.46 121.92) (xy 137.16 121.92)
		)
		(stroke
			(width 0)
			(type default)
		)
	)
	(wire
		(pts
			(xy 66.04 185.42) (xy 66.04 187.96)
		)
		(stroke
			(width 0)
			(type default)
		)
	)
	(wire
		(pts
			(xy 261.62 218.44) (xy 261.62 220.98)
		)
		(stroke
			(width 0)
			(type default)
		)
	)
	(wire
		(pts
			(xy 320.04 118.11) (xy 320.04 116.84)
		)
		(stroke
			(width 0)
			(type default)
		)
	)
	(wire
		(pts
			(xy 137.16 134.62) (xy 147.32 134.62)
		)
		(stroke
			(width 0)
			(type default)
		)
	)
	(wire
		(pts
			(xy 334.01 193.04) (xy 334.01 194.31)
		)
		(stroke
			(width 0)
			(type default)
		)
	)
	(wire
		(pts
			(xy 62.23 207.01) (xy 62.23 210.82)
		)
		(stroke
			(width 0)
			(type default)
		)
	)
	(wire
		(pts
			(xy 256.54 110.49) (xy 256.54 107.95)
		)
		(stroke
			(width 0)
			(type default)
		)
	)
	(wire
		(pts
			(xy 345.44 110.49) (xy 345.44 113.03)
		)
		(stroke
			(width 0)
			(type default)
		)
	)
	(wire
		(pts
			(xy 46.99 166.37) (xy 66.04 166.37)
		)
		(stroke
			(width 0)
			(type default)
		)
	)
	(wire
		(pts
			(xy 388.62 121.92) (xy 388.62 123.19)
		)
		(stroke
			(width 0)
			(type default)
		)
	)
	(wire
		(pts
			(xy 388.62 173.99) (xy 389.89 173.99)
		)
		(stroke
			(width 0)
			(type default)
		)
	)
	(wire
		(pts
			(xy 294.64 123.19) (xy 281.94 123.19)
		)
		(stroke
			(width 0)
			(type default)
		)
	)
	(wire
		(pts
			(xy 78.74 111.76) (xy 85.09 111.76)
		)
		(stroke
			(width 0)
			(type default)
		)
	)
	(wire
		(pts
			(xy 87.63 140.97) (xy 87.63 143.51)
		)
		(stroke
			(width 0)
			(type default)
		)
	)
	(wire
		(pts
			(xy 49.53 209.55) (xy 49.53 210.82)
		)
		(stroke
			(width 0)
			(type default)
		)
	)
	(wire
		(pts
			(xy 261.62 172.72) (xy 261.62 175.26)
		)
		(stroke
			(width 0)
			(type default)
		)
	)
	(wire
		(pts
			(xy 279.4 227.33) (xy 279.4 226.06)
		)
		(stroke
			(width 0)
			(type default)
		)
	)
	(wire
		(pts
			(xy 289.56 185.42) (xy 290.83 185.42)
		)
		(stroke
			(width 0)
			(type default)
		)
	)
	(wire
		(pts
			(xy 43.18 121.92) (xy 43.18 124.46)
		)
		(stroke
			(width 0)
			(type default)
		)
	)
	(wire
		(pts
			(xy 175.26 139.7) (xy 175.26 144.78)
		)
		(stroke
			(width 0)
			(type default)
		)
	)
	(polyline
		(pts
			(xy 219.71 201.93) (xy 407.67 201.93)
		)
		(stroke
			(width 0)
			(type default)
		)
	)
	(wire
		(pts
			(xy 67.31 229.87) (xy 66.04 229.87)
		)
		(stroke
			(width 0)
			(type default)
		)
	)
	(wire
		(pts
			(xy 137.16 110.49) (xy 137.16 121.92)
		)
		(stroke
			(width 0)
			(type default)
		)
	)
	(wire
		(pts
			(xy 317.5 110.49) (xy 320.04 110.49)
		)
		(stroke
			(width 0)
			(type default)
		)
	)
	(wire
		(pts
			(xy 334.01 228.6) (xy 334.01 231.14)
		)
		(stroke
			(width 0)
			(type default)
		)
	)
	(wire
		(pts
			(xy 43.18 120.65) (xy 43.18 121.92)
		)
		(stroke
			(width 0)
			(type default)
		)
	)
	(wire
		(pts
			(xy 388.62 184.15) (xy 388.62 185.42)
		)
		(stroke
			(width 0)
			(type default)
		)
	)
	(wire
		(pts
			(xy 85.09 111.76) (xy 85.09 121.92)
		)
		(stroke
			(width 0)
			(type default)
		)
	)
	(wire
		(pts
			(xy 171.45 120.65) (xy 171.45 121.92)
		)
		(stroke
			(width 0)
			(type default)
		)
	)
	(wire
		(pts
			(xy 388.62 227.33) (xy 388.62 228.6)
		)
		(stroke
			(width 0)
			(type default)
		)
	)
	(wire
		(pts
			(xy 318.77 180.34) (xy 321.31 180.34)
		)
		(stroke
			(width 0)
			(type default)
		)
	)
	(wire
		(pts
			(xy 323.85 137.16) (xy 323.85 134.62)
		)
		(stroke
			(width 0)
			(type default)
		)
	)
	(wire
		(pts
			(xy 279.4 226.06) (xy 290.83 226.06)
		)
		(stroke
			(width 0)
			(type default)
		)
	)
	(wire
		(pts
			(xy 388.62 220.98) (xy 388.62 219.71)
		)
		(stroke
			(width 0)
			(type default)
		)
	)
	(wire
		(pts
			(xy 137.16 129.54) (xy 137.16 134.62)
		)
		(stroke
			(width 0)
			(type default)
		)
	)
	(wire
		(pts
			(xy 317.5 118.11) (xy 320.04 118.11)
		)
		(stroke
			(width 0)
			(type default)
		)
	)
	(label "EN_5V"
		(at 288.29 123.19 0)
		(effects
			(font
				(size 1.27 1.27)
			)
			(justify left bottom)
		)
	)
	(label "OUT_M2"
		(at 335.28 175.26 0)
		(effects
			(font
				(size 1.27 1.27)
			)
			(justify left bottom)
		)
	)
	(label "SW_M2"
		(at 312.42 175.26 0)
		(effects
			(font
				(size 1.27 1.27)
			)
			(justify left bottom)
		)
	)
	(label "VCC_IN"
		(at 115.57 121.92 0)
		(effects
			(font
				(size 1.27 1.27)
			)
			(justify left bottom)
		)
	)
	(label "FB_M2"
		(at 325.12 185.42 0)
		(effects
			(font
				(size 1.27 1.27)
			)
			(justify left bottom)
		)
	)
	(label "FB_3V3"
		(at 325.12 231.14 0)
		(effects
			(font
				(size 1.27 1.27)
			)
			(justify left bottom)
		)
	)
	(label "SW_3V3"
		(at 311.15 220.98 0)
		(effects
			(font
				(size 1.27 1.27)
			)
			(justify left bottom)
		)
	)
	(label "OUT_3V3"
		(at 335.28 220.98 0)
		(effects
			(font
				(size 1.27 1.27)
			)
			(justify left bottom)
		)
	)
	(label "EN_3V3"
		(at 284.48 226.06 0)
		(effects
			(font
				(size 1.27 1.27)
			)
			(justify left bottom)
		)
	)
	(label "SW_5V"
		(at 320.04 110.49 0)
		(effects
			(font
				(size 1.27 1.27)
			)
			(justify left bottom)
		)
	)
	(label "FB_5V"
		(at 320.04 123.19 0)
		(effects
			(font
				(size 1.27 1.27)
			)
			(justify left bottom)
		)
	)
	(label "OUT_5V"
		(at 346.71 110.49 0)
		(effects
			(font
				(size 1.27 1.27)
			)
			(justify left bottom)
		)
	)
	(label "VCC_5V"
		(at 320.04 128.27 0)
		(effects
			(font
				(size 1.27 1.27)
			)
			(justify left bottom)
		)
	)
	(global_label "3V3_SSD"
		(shape output)
		(at 372.11 175.26 0)
		(fields_autoplaced yes)
		(effects
			(font
				(size 1.27 1.27)
			)
			(justify left)
		)
		(property "Intersheetrefs" "${INTERSHEET_REFS}"
			(at 382.5985 175.1806 0)
			(effects
				(font
					(size 1.27 1.27)
				)
				(justify left)
				(hide yes)
			)
		)
	)
	(global_label "3V3_SSD"
		(shape output)
		(at 389.89 173.99 0)
		(fields_autoplaced yes)
		(effects
			(font
				(size 1.27 1.27)
			)
			(justify left)
		)
		(property "Intersheetrefs" "${INTERSHEET_REFS}"
			(at 400.3785 173.9106 0)
			(effects
				(font
					(size 1.27 1.27)
				)
				(justify left)
				(hide yes)
			)
		)
	)
	(hierarchical_label "POE_12V"
		(shape input)
		(at 46.99 166.37 180)
		(effects
			(font
				(size 1.27 1.27)
			)
			(justify right)
		)
	)
	(hierarchical_label "V_{BUS}"
		(shape input)
		(at 46.99 210.82 180)
		(effects
			(font
				(size 1.27 1.27)
			)
			(justify right)
		)
	)
	(hierarchical_label "NVMe_EN"
		(shape input)
		(at 283.21 180.34 180)
		(effects
			(font
				(size 1.27 1.27)
			)
			(justify right)
		)
	)
	(symbol
		(lib_id "antmicroCapacitorsmisc:C_22u_25V_0805")
		(at 363.22 113.03 90)
		(mirror x)
		(unit 1)
		(exclude_from_sim no)
		(in_bom yes)
		(on_board yes)
		(dnp no)
		(fields_autoplaced yes)
		(property "Reference" "C318"
			(at 360.68 113.0362 90)
			(effects
				(font
					(size 1.27 1.27)
				)
				(justify left)
			)
		)
		(property "Value" "C_22u_25V_0805"
			(at 367.03 113.03 0)
			(effects
				(font
					(size 1.27 1.27)
				)
				(justify left bottom)
				(hide yes)
			)
		)
		(property "Footprint" "antmicro-footprints:C_0805_2012Metric"
			(at 358.14 118.11 0)
			(effects
				(font
					(size 1.524 1.524)
				)
				(justify left bottom)
				(hide yes)
			)
		)
		(property "Datasheet" "https://product.samsungsem.com/mlcc/CL21A226MAYNNN.do"
			(at 363.22 113.03 0)
			(effects
				(font
					(size 1.27 1.27)
				)
				(justify left bottom)
				(hide yes)
			)
		)
		(property "Description" ""
			(at 363.22 113.03 0)
			(effects
				(font
					(size 1.27 1.27)
				)
				(hide yes)
			)
		)
		(property "Manufacturer" "Samsung Electro-Mechanics"
			(at 353.06 118.11 0)
			(effects
				(font
					(size 1.524 1.524)
				)
				(justify left bottom)
				(hide yes)
			)
		)
		(property "MPN" "CL21A226MAYNNNE"
			(at 355.6 118.11 0)
			(effects
				(font
					(size 1.524 1.524)
				)
				(justify left bottom)
				(hide yes)
			)
		)
		(property "Val" "22u"
			(at 360.68 115.5762 90)
			(effects
				(font
					(size 1.27 1.27)
				)
				(justify left)
			)
		)
		(property "License" "Apache-2.0"
			(at 386.08 133.35 0)
			(effects
				(font
					(size 1.27 1.27)
					(thickness 0.15)
				)
				(justify left bottom)
				(hide yes)
			)
		)
		(property "Author" "Antmicro"
			(at 388.62 133.35 0)
			(effects
				(font
					(size 1.27 1.27)
					(thickness 0.15)
				)
				(justify left bottom)
				(hide yes)
			)
		)
		(property "Voltage" "25V"
			(at 360.68 118.1162 90)
			(effects
				(font
					(size 1.27 1.27)
				)
				(justify left)
			)
		)
		(property "Dielectric" "X5R"
			(at 393.7 133.35 0)
			(effects
				(font
					(size 1.27 1.27)
				)
				(justify left bottom)
				(hide yes)
			)
		)
		(property "Public" "False"
			(at 396.24 133.35 0)
			(effects
				(font
					(size 1.27 1.27)
				)
				(justify left bottom)
				(hide yes)
			)
		)
		(pin "1"
		)
		(pin "2"
		)
		(instances
			(project "cm4-baseboard"
				(path ""
					(reference "C318")
					(unit 1)
				)
			)
		)
	)
	(symbol
		(lib_id "antmicroCapacitors0402:C_100n_0402")
		(at 320.04 111.76 270)
		(unit 1)
		(exclude_from_sim no)
		(in_bom yes)
		(on_board yes)
		(dnp no)
		(property "Reference" "C310"
			(at 322.58 113.03 90)
			(effects
				(font
					(size 1.27 1.27)
				)
				(justify left)
			)
		)
		(property "Value" "C_100n_0402"
			(at 316.23 111.76 0)
			(effects
				(font
					(size 1.27 1.27)
				)
				(justify left bottom)
				(hide yes)
			)
		)
		(property "Footprint" "antmicro-footprints:C_0402_1005Metric"
			(at 325.12 116.84 0)
			(effects
				(font
					(size 1.524 1.524)
				)
				(justify left bottom)
				(hide yes)
			)
		)
		(property "Datasheet" "https://www.murata.com/products/productdetail?partno=GRM155R61H104KE14%23"
			(at 320.04 111.76 0)
			(effects
				(font
					(size 1.27 1.27)
				)
				(justify left bottom)
				(hide yes)
			)
		)
		(property "Description" ""
			(at 320.04 111.76 0)
			(effects
				(font
					(size 1.27 1.27)
				)
				(hide yes)
			)
		)
		(property "Manufacturer" "Murata"
			(at 330.2 116.84 0)
			(effects
				(font
					(size 1.524 1.524)
				)
				(justify left bottom)
				(hide yes)
			)
		)
		(property "MPN" "GRM155R61H104KE14D"
			(at 327.66 116.84 0)
			(effects
				(font
					(size 1.524 1.524)
				)
				(justify left bottom)
				(hide yes)
			)
		)
		(property "Val" "100n"
			(at 322.58 115.57 90)
			(effects
				(font
					(size 1.27 1.27)
				)
				(justify left)
			)
		)
		(property "License" "Apache-2.0"
			(at 297.18 132.08 0)
			(effects
				(font
					(size 1.27 1.27)
					(thickness 0.15)
				)
				(justify left bottom)
				(hide yes)
			)
		)
		(property "Author" "Antmicro"
			(at 294.64 132.08 0)
			(effects
				(font
					(size 1.27 1.27)
					(thickness 0.15)
				)
				(justify left bottom)
				(hide yes)
			)
		)
		(property "Voltage" "50V"
			(at 292.1 132.08 0)
			(effects
				(font
					(size 1.27 1.27)
				)
				(justify left bottom)
				(hide yes)
			)
		)
		(property "Dielectric" "X5R"
			(at 289.56 132.08 0)
			(effects
				(font
					(size 1.27 1.27)
				)
				(justify left bottom)
				(hide yes)
			)
		)
		(pin "1"
		)
		(pin "2"
		)
		(instances
			(project "cm4-baseboard"
				(path ""
					(reference "C310")
					(unit 1)
				)
			)
		)
	)
	(symbol
		(lib_id "antmicroResistors0402:R_470k_0402")
		(at 87.63 237.49 90)
		(unit 1)
		(exclude_from_sim no)
		(in_bom yes)
		(on_board yes)
		(dnp no)
		(property "Reference" "R306"
			(at 88.9 233.68 90)
			(effects
				(font
					(size 1.27 1.27)
					(thickness 0.15)
				)
				(justify right)
			)
		)
		(property "Value" "R_470k_0402"
			(at 100.33 217.17 0)
			(effects
				(font
					(size 1.27 1.27)
					(thickness 0.15)
				)
				(justify left bottom)
				(hide yes)
			)
		)
		(property "Footprint" "antmicro-footprints:R_0402_1005Metric"
			(at 102.87 217.17 0)
			(effects
				(font
					(size 1.27 1.27)
					(thickness 0.15)
				)
				(justify left bottom)
				(hide yes)
			)
		)
		(property "Datasheet" "https://www.bourns.com/docs/product-datasheets/cr.pdf"
			(at 105.41 217.17 0)
			(effects
				(font
					(size 1.27 1.27)
					(thickness 0.15)
				)
				(justify left bottom)
				(hide yes)
			)
		)
		(property "Description" ""
			(at 87.63 237.49 0)
			(effects
				(font
					(size 1.27 1.27)
				)
				(hide yes)
			)
		)
		(property "MPN" "CR0402-FX-4703GLF"
			(at 107.95 217.17 0)
			(effects
				(font
					(size 1.27 1.27)
					(thickness 0.15)
				)
				(justify left bottom)
				(hide yes)
			)
		)
		(property "Manufacturer" "Bourns"
			(at 110.49 217.17 0)
			(effects
				(font
					(size 1.27 1.27)
					(thickness 0.15)
				)
				(justify left bottom)
				(hide yes)
			)
		)
		(property "License" "Apache-2.0"
			(at 113.03 217.17 0)
			(effects
				(font
					(size 1.27 1.27)
					(thickness 0.15)
				)
				(justify left bottom)
				(hide yes)
			)
		)
		(property "Author" "Antmicro"
			(at 115.57 217.17 0)
			(effects
				(font
					(size 1.27 1.27)
					(thickness 0.15)
				)
				(justify left bottom)
				(hide yes)
			)
		)
		(property "Val" "470k"
			(at 88.9 236.22 90)
			(effects
				(font
					(size 1.27 1.27)
					(thickness 0.15)
				)
				(justify right)
			)
		)
		(property "Tolerance" "1%"
			(at 97.79 217.17 0)
			(effects
				(font
					(size 1.27 1.27)
				)
				(justify left bottom)
				(hide yes)
			)
		)
		(pin "1"
		)
		(pin "2"
		)
		(instances
			(project "cm4-baseboard"
				(path ""
					(reference "R306")
					(unit 1)
				)
			)
		)
	)
	(symbol
		(lib_id "antmicroCapacitorsmisc:C_22u_25V_0805")
		(at 345.44 227.33 90)
		(mirror x)
		(unit 1)
		(exclude_from_sim no)
		(in_bom yes)
		(on_board yes)
		(dnp no)
		(fields_autoplaced yes)
		(property "Reference" "C314"
			(at 347.98 227.3363 90)
			(effects
				(font
					(size 1.27 1.27)
				)
				(justify right)
			)
		)
		(property "Value" "C_22u_25V_0805"
			(at 349.25 227.33 0)
			(effects
				(font
					(size 1.27 1.27)
				)
				(justify left bottom)
				(hide yes)
			)
		)
		(property "Footprint" "antmicro-footprints:C_0805_2012Metric"
			(at 340.36 232.41 0)
			(effects
				(font
					(size 1.524 1.524)
				)
				(justify left bottom)
				(hide yes)
			)
		)
		(property "Datasheet" "https://product.samsungsem.com/mlcc/CL21A226MAYNNN.do"
			(at 345.44 227.33 0)
			(effects
				(font
					(size 1.27 1.27)
				)
				(justify left bottom)
				(hide yes)
			)
		)
		(property "Description" ""
			(at 345.44 227.33 0)
			(effects
				(font
					(size 1.27 1.27)
				)
				(hide yes)
			)
		)
		(property "Manufacturer" "Samsung Electro-Mechanics"
			(at 335.28 232.41 0)
			(effects
				(font
					(size 1.524 1.524)
				)
				(justify left bottom)
				(hide yes)
			)
		)
		(property "MPN" "CL21A226MAYNNNE"
			(at 337.82 232.41 0)
			(effects
				(font
					(size 1.524 1.524)
				)
				(justify left bottom)
				(hide yes)
			)
		)
		(property "Val" "22u"
			(at 347.98 229.8763 90)
			(effects
				(font
					(size 1.27 1.27)
				)
				(justify right)
			)
		)
		(property "License" "Apache-2.0"
			(at 368.3 247.65 0)
			(effects
				(font
					(size 1.27 1.27)
					(thickness 0.15)
				)
				(justify left bottom)
				(hide yes)
			)
		)
		(property "Author" "Antmicro"
			(at 370.84 247.65 0)
			(effects
				(font
					(size 1.27 1.27)
					(thickness 0.15)
				)
				(justify left bottom)
				(hide yes)
			)
		)
		(property "Voltage" "25V"
			(at 347.98 232.4163 90)
			(effects
				(font
					(size 1.27 1.27)
				)
				(justify right)
			)
		)
		(property "Dielectric" "X5R"
			(at 375.92 247.65 0)
			(effects
				(font
					(size 1.27 1.27)
				)
				(justify left bottom)
				(hide yes)
			)
		)
		(property "Public" "False"
			(at 378.46 247.65 0)
			(effects
				(font
					(size 1.27 1.27)
				)
				(justify left bottom)
				(hide yes)
			)
		)
		(pin "1"
		)
		(pin "2"
		)
		(instances
			(project "cm4-baseboard"
				(path ""
					(reference "C314")
					(unit 1)
				)
			)
		)
	)
	(symbol
		(lib_id "antmicroFixedInductors:L_1u8_14A_Coilcraft-XAL6030")
		(at 327.66 110.49 0)
		(unit 1)
		(exclude_from_sim no)
		(in_bom yes)
		(on_board yes)
		(dnp no)
		(fields_autoplaced yes)
		(property "Reference" "L303"
			(at 330.2 105.41 0)
			(effects
				(font
					(size 1.27 1.27)
				)
			)
		)
		(property "Value" "L_1u8_14A_Coilcraft-XAL6030"
			(at 330.2 105.41 0)
			(effects
				(font
					(size 1.27 1.27)
				)
				(hide yes)
			)
		)
		(property "Footprint" "antmicro-footprints:L_Coilcraft-XAL6030"
			(at 349.885 101.6 0)
			(effects
				(font
					(size 1.524 1.524)
				)
				(justify left bottom)
				(hide yes)
			)
		)
		(property "Datasheet" "https://www.mouser.com/datasheet/2/597/xal60xx-270658.pdf"
			(at 327.66 110.49 0)
			(effects
				(font
					(size 1.524 1.524)
				)
				(justify left bottom)
				(hide yes)
			)
		)
		(property "Description" ""
			(at 327.66 110.49 0)
			(effects
				(font
					(size 1.27 1.27)
				)
				(hide yes)
			)
		)
		(property "Manufacturer" "Coilcraft"
			(at 331.47 93.98 0)
			(effects
				(font
					(size 1.27 1.27)
				)
				(justify left bottom)
				(hide yes)
			)
		)
		(property "MPN" "XAL6030-182MEC"
			(at 322.58 105.41 0)
			(effects
				(font
					(size 1.27 1.27)
				)
				(justify left bottom)
				(hide yes)
			)
		)
		(property "Size" "6.36x6.56"
			(at 332.105 99.695 0)
			(effects
				(font
					(size 1.27 1.27)
				)
				(justify left bottom)
				(hide yes)
			)
		)
		(property "Val" "1.8u/14A"
			(at 330.2 107.95 0)
			(effects
				(font
					(size 1.27 1.27)
				)
			)
		)
		(property "Author" "Antmicro"
			(at 342.9 133.35 0)
			(effects
				(font
					(size 1.27 1.27)
					(thickness 0.15)
				)
				(justify left bottom)
				(hide yes)
			)
		)
		(property "License" "Apache-2.0"
			(at 342.9 135.89 0)
			(effects
				(font
					(size 1.27 1.27)
					(thickness 0.15)
				)
				(justify left bottom)
				(hide yes)
			)
		)
		(property "ISat" "18.2 A"
			(at 16.51 237.49 0)
			(effects
				(font
					(size 1.27 1.27)
				)
				(hide yes)
			)
		)
		(property "IMax" "14 A"
			(at 16.51 237.49 0)
			(effects
				(font
					(size 1.27 1.27)
				)
				(hide yes)
			)
		)
		(pin "1"
		)
		(pin "2"
		)
		(instances
			(project "cm4-baseboard"
				(path ""
					(reference "L303")
					(unit 1)
				)
			)
		)
	)
	(symbol
		(lib_id "antmicropower:GND")
		(at 289.56 234.95 0)
		(unit 1)
		(exclude_from_sim no)
		(in_bom yes)
		(on_board yes)
		(dnp no)
		(fields_autoplaced yes)
		(property "Reference" "#PWR0325"
			(at 298.45 237.49 0)
			(effects
				(font
					(size 1.27 1.27)
					(thickness 0.15)
				)
				(justify left bottom)
				(hide yes)
			)
		)
		(property "Value" "GND"
			(at 287.5498 240.03 0)
			(effects
				(font
					(size 1.27 1.27)
					(thickness 0.15)
				)
				(justify left bottom)
			)
		)
		(property "Footprint" ""
			(at 298.45 242.57 0)
			(effects
				(font
					(size 1.27 1.27)
					(thickness 0.15)
				)
				(justify left bottom)
				(hide yes)
			)
		)
		(property "Datasheet" ""
			(at 298.45 247.65 0)
			(effects
				(font
					(size 1.27 1.27)
					(thickness 0.15)
				)
				(justify left bottom)
				(hide yes)
			)
		)
		(property "Description" ""
			(at 289.56 234.95 0)
			(effects
				(font
					(size 1.27 1.27)
				)
				(hide yes)
			)
		)
		(property "Author" "Antmicro"
			(at 298.45 242.57 0)
			(effects
				(font
					(size 1.27 1.27)
					(thickness 0.15)
				)
				(justify left bottom)
				(hide yes)
			)
		)
		(property "License" "Apache-2.0"
			(at 298.45 245.11 0)
			(effects
				(font
					(size 1.27 1.27)
					(thickness 0.15)
				)
				(justify left bottom)
				(hide yes)
			)
		)
		(pin "1"
		)
		(instances
			(project "cm4-baseboard"
				(path ""
					(reference "#PWR0325")
					(unit 1)
				)
			)
		)
	)
	(symbol
		(lib_id "antmicropower:GND")
		(at 273.05 119.38 0)
		(unit 1)
		(exclude_from_sim no)
		(in_bom yes)
		(on_board yes)
		(dnp no)
		(property "Reference" "#PWR0321"
			(at 273.05 125.73 0)
			(effects
				(font
					(size 1.27 1.27)
				)
				(justify left bottom)
				(hide yes)
			)
		)
		(property "Value" "GND"
			(at 273.05 123.19 0)
			(effects
				(font
					(size 1.27 1.27)
				)
			)
		)
		(property "Footprint" ""
			(at 281.94 127 0)
			(effects
				(font
					(size 1.27 1.27)
					(thickness 0.15)
				)
				(justify left bottom)
				(hide yes)
			)
		)
		(property "Datasheet" ""
			(at 281.94 132.08 0)
			(effects
				(font
					(size 1.27 1.27)
					(thickness 0.15)
				)
				(justify left bottom)
				(hide yes)
			)
		)
		(property "Description" ""
			(at 273.05 119.38 0)
			(effects
				(font
					(size 1.27 1.27)
				)
				(hide yes)
			)
		)
		(property "Author" "Antmicro"
			(at 281.94 127 0)
			(effects
				(font
					(size 1.27 1.27)
					(thickness 0.15)
				)
				(justify left bottom)
				(hide yes)
			)
		)
		(property "License" "Apache-2.0"
			(at 281.94 129.54 0)
			(effects
				(font
					(size 1.27 1.27)
					(thickness 0.15)
				)
				(justify left bottom)
				(hide yes)
			)
		)
		(pin "1"
		)
		(instances
			(project "cm4-baseboard"
				(path ""
					(reference "#PWR0321")
					(unit 1)
				)
			)
		)
	)
	(symbol
		(lib_id "antmicroCapacitors0402:C_1u_0402")
		(at 323.85 134.62 90)
		(unit 1)
		(exclude_from_sim no)
		(in_bom yes)
		(on_board yes)
		(dnp no)
		(property "Reference" "C311"
			(at 324.485 130.175 90)
			(effects
				(font
					(size 1.27 1.27)
				)
				(justify right)
			)
		)
		(property "Value" "C_1u_0402"
			(at 327.66 134.62 0)
			(effects
				(font
					(size 1.27 1.27)
				)
				(justify left bottom)
				(hide yes)
			)
		)
		(property "Footprint" "antmicro-footprints:C_0402_1005Metric"
			(at 318.77 129.54 0)
			(effects
				(font
					(size 1.524 1.524)
				)
				(justify left bottom)
				(hide yes)
			)
		)
		(property "Datasheet" "https://product.tdk.com/en/search/capacitor/ceramic/mlcc/info?part_no=C1005X6S1A105K050BC"
			(at 323.85 134.62 0)
			(effects
				(font
					(size 1.27 1.27)
				)
				(justify left bottom)
				(hide yes)
			)
		)
		(property "Description" ""
			(at 323.85 134.62 0)
			(effects
				(font
					(size 1.27 1.27)
				)
				(hide yes)
			)
		)
		(property "Manufacturer" "TDK"
			(at 313.69 129.54 0)
			(effects
				(font
					(size 1.524 1.524)
				)
				(justify left bottom)
				(hide yes)
			)
		)
		(property "MPN" "C1005X6S1A105K050BC"
			(at 316.23 129.54 0)
			(effects
				(font
					(size 1.524 1.524)
				)
				(justify left bottom)
				(hide yes)
			)
		)
		(property "Val" "1u"
			(at 324.485 133.985 90)
			(effects
				(font
					(size 1.27 1.27)
				)
				(justify right)
			)
		)
		(property "License" "Apache-2.0"
			(at 346.71 114.3 0)
			(effects
				(font
					(size 1.27 1.27)
					(thickness 0.15)
				)
				(justify left bottom)
				(hide yes)
			)
		)
		(property "Author" "Antmicro"
			(at 349.25 114.3 0)
			(effects
				(font
					(size 1.27 1.27)
					(thickness 0.15)
				)
				(justify left bottom)
				(hide yes)
			)
		)
		(property "Voltage" ""
			(at 351.79 114.3 0)
			(effects
				(font
					(size 1.27 1.27)
				)
				(justify left bottom)
				(hide yes)
			)
		)
		(property "Dielectric" ""
			(at 354.33 114.3 0)
			(effects
				(font
					(size 1.27 1.27)
				)
				(justify left bottom)
				(hide yes)
			)
		)
		(pin "1"
		)
		(pin "2"
		)
		(instances
			(project "cm4-baseboard"
				(path ""
					(reference "C311")
					(unit 1)
				)
			)
		)
	)
	(symbol
		(lib_id "antmicroResistors0402:R_1k_0402")
		(at 388.62 121.92 90)
		(unit 1)
		(exclude_from_sim no)
		(in_bom yes)
		(on_board yes)
		(dnp no)
		(fields_autoplaced yes)
		(property "Reference" "R325"
			(at 391.16 118.11 90)
			(effects
				(font
					(size 1.27 1.27)
					(thickness 0.15)
				)
				(justify right)
			)
		)
		(property "Value" "R_1k_0402"
			(at 401.32 101.6 0)
			(effects
				(font
					(size 1.27 1.27)
					(thickness 0.15)
				)
				(justify left bottom)
				(hide yes)
			)
		)
		(property "Footprint" "antmicro-footprints:R_0402_1005Metric"
			(at 403.86 101.6 0)
			(effects
				(font
					(size 1.27 1.27)
					(thickness 0.15)
				)
				(justify left bottom)
				(hide yes)
			)
		)
		(property "Datasheet" "https://www.bourns.com/docs/product-datasheets/cr.pdf"
			(at 406.4 101.6 0)
			(effects
				(font
					(size 1.27 1.27)
					(thickness 0.15)
				)
				(justify left bottom)
				(hide yes)
			)
		)
		(property "Description" ""
			(at 388.62 121.92 0)
			(effects
				(font
					(size 1.27 1.27)
				)
				(hide yes)
			)
		)
		(property "MPN" "CR0402-FX-1001GLF"
			(at 408.94 101.6 0)
			(effects
				(font
					(size 1.27 1.27)
					(thickness 0.15)
				)
				(justify left bottom)
				(hide yes)
			)
		)
		(property "Manufacturer" "Bourns"
			(at 411.48 101.6 0)
			(effects
				(font
					(size 1.27 1.27)
					(thickness 0.15)
				)
				(justify left bottom)
				(hide yes)
			)
		)
		(property "License" "Apache-2.0"
			(at 414.02 101.6 0)
			(effects
				(font
					(size 1.27 1.27)
					(thickness 0.15)
				)
				(justify left bottom)
				(hide yes)
			)
		)
		(property "Author" "Antmicro"
			(at 416.56 101.6 0)
			(effects
				(font
					(size 1.27 1.27)
					(thickness 0.15)
				)
				(justify left bottom)
				(hide yes)
			)
		)
		(property "Val" "1k"
			(at 391.16 120.65 90)
			(effects
				(font
					(size 1.27 1.27)
					(thickness 0.15)
				)
				(justify right)
			)
		)
		(property "Tolerance" "1%"
			(at 398.78 101.6 0)
			(effects
				(font
					(size 1.27 1.27)
				)
				(justify left bottom)
				(hide yes)
			)
		)
		(pin "1"
		)
		(pin "2"
		)
		(instances
			(project "cm4-baseboard"
				(path ""
					(reference "R325")
					(unit 1)
				)
			)
		)
	)
	(symbol
		(lib_id "antmicropower:GND")
		(at 345.44 238.76 0)
		(unit 1)
		(exclude_from_sim no)
		(in_bom yes)
		(on_board yes)
		(dnp no)
		(fields_autoplaced yes)
		(property "Reference" "#PWR0334"
			(at 354.33 241.3 0)
			(effects
				(font
					(size 1.27 1.27)
					(thickness 0.15)
				)
				(justify left bottom)
				(hide yes)
			)
		)
		(property "Value" "GND"
			(at 343.4298 243.84 0)
			(effects
				(font
					(size 1.27 1.27)
					(thickness 0.15)
				)
				(justify left bottom)
			)
		)
		(property "Footprint" ""
			(at 354.33 246.38 0)
			(effects
				(font
					(size 1.27 1.27)
					(thickness 0.15)
				)
				(justify left bottom)
				(hide yes)
			)
		)
		(property "Datasheet" ""
			(at 354.33 251.46 0)
			(effects
				(font
					(size 1.27 1.27)
					(thickness 0.15)
				)
				(justify left bottom)
				(hide yes)
			)
		)
		(property "Description" ""
			(at 345.44 238.76 0)
			(effects
				(font
					(size 1.27 1.27)
				)
				(hide yes)
			)
		)
		(property "Author" "Antmicro"
			(at 354.33 246.38 0)
			(effects
				(font
					(size 1.27 1.27)
					(thickness 0.15)
				)
				(justify left bottom)
				(hide yes)
			)
		)
		(property "License" "Apache-2.0"
			(at 354.33 248.92 0)
			(effects
				(font
					(size 1.27 1.27)
					(thickness 0.15)
				)
				(justify left bottom)
				(hide yes)
			)
		)
		(pin "1"
		)
		(instances
			(project "cm4-baseboard"
				(path ""
					(reference "#PWR0334")
					(unit 1)
				)
			)
		)
	)
	(symbol
		(lib_id "antmicroTransistorsFETsMOSFETsSingle:SQS401EN-T1_BE3")
		(at 78.74 172.72 90)
		(unit 1)
		(exclude_from_sim no)
		(in_bom yes)
		(on_board yes)
		(dnp no)
		(property "Reference" "Q305"
			(at 76.2 160.02 90)
			(effects
				(font
					(size 1.27 1.27)
					(thickness 0.15)
				)
			)
		)
		(property "Value" "SQS401EN-T1_BE3"
			(at 88.9 157.48 0)
			(effects
				(font
					(size 1.27 1.27)
					(thickness 0.15)
				)
				(justify left bottom)
				(hide yes)
			)
		)
		(property "Footprint" "antmicro-footprints:Vishay_PowerPAK_1212-8_Single"
			(at 91.44 157.48 0)
			(effects
				(font
					(size 1.27 1.27)
					(thickness 0.15)
				)
				(justify left bottom)
				(hide yes)
			)
		)
		(property "Datasheet" "https://www.vishay.com/docs/65529/sqs401en.pdf"
			(at 93.98 157.48 0)
			(effects
				(font
					(size 1.27 1.27)
					(thickness 0.15)
				)
				(justify left bottom)
				(hide yes)
			)
		)
		(property "Description" ""
			(at 78.74 172.72 0)
			(effects
				(font
					(size 1.27 1.27)
				)
				(hide yes)
			)
		)
		(property "MPN" "SQS401EN-T1_BE3"
			(at 76.2 162.56 90)
			(effects
				(font
					(size 1.27 1.27)
					(thickness 0.15)
				)
			)
		)
		(property "Manufacturer" "Vishay"
			(at 96.52 157.48 0)
			(effects
				(font
					(size 1.27 1.27)
					(thickness 0.15)
				)
				(justify left bottom)
				(hide yes)
			)
		)
		(property "Author" "Antmicro"
			(at 99.06 157.48 0)
			(effects
				(font
					(size 1.27 1.27)
					(thickness 0.15)
				)
				(justify left bottom)
				(hide yes)
			)
		)
		(property "License" "Apache-2.0"
			(at 101.6 157.48 0)
			(effects
				(font
					(size 1.27 1.27)
					(thickness 0.15)
				)
				(justify left bottom)
				(hide yes)
			)
		)
		(pin "1"
		)
		(pin "2"
		)
		(pin "3"
		)
		(pin "4"
		)
		(pin "5"
		)
		(instances
			(project "cm4-baseboard"
				(path ""
					(reference "Q305")
					(unit 1)
				)
			)
		)
	)
	(symbol
		(lib_id "antmicropower:PWR_FLAG")
		(at 372.11 218.44 0)
		(unit 1)
		(exclude_from_sim no)
		(in_bom yes)
		(on_board yes)
		(dnp no)
		(property "Reference" "#FLG08"
			(at 372.11 216.535 0)
			(effects
				(font
					(size 1.27 1.27)
				)
				(hide yes)
			)
		)
		(property "Value" "PWR_FLAG"
			(at 372.11 214.63 0)
			(effects
				(font
					(size 1.27 1.27)
				)
			)
		)
		(property "Footprint" ""
			(at 372.11 218.44 0)
			(effects
				(font
					(size 1.27 1.27)
				)
				(hide yes)
			)
		)
		(property "Datasheet" ""
			(at 372.11 218.44 0)
			(effects
				(font
					(size 1.27 1.27)
				)
				(hide yes)
			)
		)
		(property "Description" ""
			(at 372.11 218.44 0)
			(effects
				(font
					(size 1.27 1.27)
				)
				(hide yes)
			)
		)
		(pin "1"
		)
		(instances
			(project "cm4-baseboard"
				(path ""
					(reference "#FLG08")
					(unit 1)
				)
			)
		)
	)
	(symbol
		(lib_id "antmicroCapacitorsmisc:C_22u_25V_0805")
		(at 355.6 227.33 90)
		(mirror x)
		(unit 1)
		(exclude_from_sim no)
		(in_bom yes)
		(on_board yes)
		(dnp no)
		(fields_autoplaced yes)
		(property "Reference" "C317"
			(at 358.14 227.3363 90)
			(effects
				(font
					(size 1.27 1.27)
				)
				(justify right)
			)
		)
		(property "Value" "C_22u_25V_0805"
			(at 359.41 227.33 0)
			(effects
				(font
					(size 1.27 1.27)
				)
				(justify left bottom)
				(hide yes)
			)
		)
		(property "Footprint" "antmicro-footprints:C_0805_2012Metric"
			(at 350.52 232.41 0)
			(effects
				(font
					(size 1.524 1.524)
				)
				(justify left bottom)
				(hide yes)
			)
		)
		(property "Datasheet" "https://product.samsungsem.com/mlcc/CL21A226MAYNNN.do"
			(at 355.6 227.33 0)
			(effects
				(font
					(size 1.27 1.27)
				)
				(justify left bottom)
				(hide yes)
			)
		)
		(property "Description" ""
			(at 355.6 227.33 0)
			(effects
				(font
					(size 1.27 1.27)
				)
				(hide yes)
			)
		)
		(property "Manufacturer" "Samsung Electro-Mechanics"
			(at 345.44 232.41 0)
			(effects
				(font
					(size 1.524 1.524)
				)
				(justify left bottom)
				(hide yes)
			)
		)
		(property "MPN" "CL21A226MAYNNNE"
			(at 347.98 232.41 0)
			(effects
				(font
					(size 1.524 1.524)
				)
				(justify left bottom)
				(hide yes)
			)
		)
		(property "Val" "22u"
			(at 358.14 229.8763 90)
			(effects
				(font
					(size 1.27 1.27)
				)
				(justify right)
			)
		)
		(property "License" "Apache-2.0"
			(at 378.46 247.65 0)
			(effects
				(font
					(size 1.27 1.27)
					(thickness 0.15)
				)
				(justify left bottom)
				(hide yes)
			)
		)
		(property "Author" "Antmicro"
			(at 381 247.65 0)
			(effects
				(font
					(size 1.27 1.27)
					(thickness 0.15)
				)
				(justify left bottom)
				(hide yes)
			)
		)
		(property "Voltage" "25V"
			(at 358.14 232.4163 90)
			(effects
				(font
					(size 1.27 1.27)
				)
				(justify right)
			)
		)
		(property "Dielectric" "X5R"
			(at 386.08 247.65 0)
			(effects
				(font
					(size 1.27 1.27)
				)
				(justify left bottom)
				(hide yes)
			)
		)
		(property "Public" "False"
			(at 388.62 247.65 0)
			(effects
				(font
					(size 1.27 1.27)
				)
				(justify left bottom)
				(hide yes)
			)
		)
		(pin "1"
		)
		(pin "2"
		)
		(instances
			(project "cm4-baseboard"
				(path ""
					(reference "C317")
					(unit 1)
				)
			)
		)
	)
	(symbol
		(lib_id "antmicropower:PWR_FLAG")
		(at 59.69 120.65 0)
		(unit 1)
		(exclude_from_sim no)
		(in_bom yes)
		(on_board yes)
		(dnp no)
		(property "Reference" "#FLG04"
			(at 59.69 118.745 0)
			(effects
				(font
					(size 1.27 1.27)
				)
				(hide yes)
			)
		)
		(property "Value" "PWR_FLAG"
			(at 59.69 116.84 0)
			(effects
				(font
					(size 1.27 1.27)
				)
			)
		)
		(property "Footprint" ""
			(at 59.69 120.65 0)
			(effects
				(font
					(size 1.27 1.27)
				)
				(hide yes)
			)
		)
		(property "Datasheet" ""
			(at 59.69 120.65 0)
			(effects
				(font
					(size 1.27 1.27)
				)
				(hide yes)
			)
		)
		(property "Description" ""
			(at 59.69 120.65 0)
			(effects
				(font
					(size 1.27 1.27)
				)
				(hide yes)
			)
		)
		(pin "1"
		)
		(instances
			(project "cm4-baseboard"
				(path ""
					(reference "#FLG04")
					(unit 1)
				)
			)
		)
	)
	(symbol
		(lib_id "antmicroResistors0402:R_10k_0402")
		(at 175.26 129.54 90)
		(unit 1)
		(exclude_from_sim no)
		(in_bom yes)
		(on_board yes)
		(dnp no)
		(fields_autoplaced yes)
		(property "Reference" "R310"
			(at 177.8 125.7299 90)
			(effects
				(font
					(size 1.27 1.27)
				)
				(justify right)
			)
		)
		(property "Value" "R_10k_0402"
			(at 179.07 129.54 0)
			(effects
				(font
					(size 1.27 1.27)
				)
				(justify left bottom)
				(hide yes)
			)
		)
		(property "Footprint" "antmicro-footprints:R_0402_1005Metric"
			(at 170.18 124.46 0)
			(effects
				(font
					(size 1.524 1.524)
				)
				(justify left bottom)
				(hide yes)
			)
		)
		(property "Datasheet" "https://www.bourns.com/docs/product-datasheets/cr.pdf"
			(at 175.26 129.54 0)
			(effects
				(font
					(size 1.27 1.27)
				)
				(justify left bottom)
				(hide yes)
			)
		)
		(property "Description" ""
			(at 175.26 129.54 0)
			(effects
				(font
					(size 1.27 1.27)
				)
				(hide yes)
			)
		)
		(property "Manufacturer" "Bourns"
			(at 165.1 124.46 0)
			(effects
				(font
					(size 1.524 1.524)
				)
				(justify left bottom)
				(hide yes)
			)
		)
		(property "MPN" "CR0402-FX-1002GLF"
			(at 167.64 124.46 0)
			(effects
				(font
					(size 1.524 1.524)
				)
				(justify left bottom)
				(hide yes)
			)
		)
		(property "Val" "10k"
			(at 177.8 128.2699 90)
			(effects
				(font
					(size 1.27 1.27)
				)
				(justify right)
			)
		)
		(property "License" "Apache-2.0"
			(at 200.66 109.22 0)
			(effects
				(font
					(size 1.27 1.27)
					(thickness 0.15)
				)
				(justify left bottom)
				(hide yes)
			)
		)
		(property "Author" "Antmicro"
			(at 203.2 109.22 0)
			(effects
				(font
					(size 1.27 1.27)
					(thickness 0.15)
				)
				(justify left bottom)
				(hide yes)
			)
		)
		(property "Tolerance" "1%"
			(at 185.42 109.22 0)
			(effects
				(font
					(size 1.27 1.27)
				)
				(justify left bottom)
				(hide yes)
			)
		)
		(pin "1"
		)
		(pin "2"
		)
		(instances
			(project "cm4-baseboard"
				(path ""
					(reference "R310")
					(unit 1)
				)
			)
		)
	)
	(symbol
		(lib_id "antmicropower:GND")
		(at 270.51 234.95 0)
		(unit 1)
		(exclude_from_sim no)
		(in_bom yes)
		(on_board yes)
		(dnp no)
		(fields_autoplaced yes)
		(property "Reference" "#PWR0320"
			(at 279.4 237.49 0)
			(effects
				(font
					(size 1.27 1.27)
					(thickness 0.15)
				)
				(justify left bottom)
				(hide yes)
			)
		)
		(property "Value" "GND"
			(at 268.4998 240.03 0)
			(effects
				(font
					(size 1.27 1.27)
					(thickness 0.15)
				)
				(justify left bottom)
			)
		)
		(property "Footprint" ""
			(at 279.4 242.57 0)
			(effects
				(font
					(size 1.27 1.27)
					(thickness 0.15)
				)
				(justify left bottom)
				(hide yes)
			)
		)
		(property "Datasheet" ""
			(at 279.4 247.65 0)
			(effects
				(font
					(size 1.27 1.27)
					(thickness 0.15)
				)
				(justify left bottom)
				(hide yes)
			)
		)
		(property "Description" ""
			(at 270.51 234.95 0)
			(effects
				(font
					(size 1.27 1.27)
				)
				(hide yes)
			)
		)
		(property "Author" "Antmicro"
			(at 279.4 242.57 0)
			(effects
				(font
					(size 1.27 1.27)
					(thickness 0.15)
				)
				(justify left bottom)
				(hide yes)
			)
		)
		(property "License" "Apache-2.0"
			(at 279.4 245.11 0)
			(effects
				(font
					(size 1.27 1.27)
					(thickness 0.15)
				)
				(justify left bottom)
				(hide yes)
			)
		)
		(pin "1"
		)
		(instances
			(project "cm4-baseboard"
				(path ""
					(reference "#PWR0320")
					(unit 1)
				)
			)
		)
	)
	(symbol
		(lib_id "antmicroLEDIndicationDiscrete:LED_G_0603_KP-1608CGCK")
		(at 388.62 128.27 270)
		(mirror x)
		(unit 1)
		(exclude_from_sim no)
		(in_bom yes)
		(on_board yes)
		(dnp no)
		(property "Reference" "D304"
			(at 394.97 124.46 90)
			(effects
				(font
					(size 1.27 1.27)
					(thickness 0.15)
				)
			)
		)
		(property "Value" "LED_G_0603_KP-1608CGCK"
			(at 381 105.41 0)
			(effects
				(font
					(size 1.27 1.27)
					(thickness 0.15)
				)
				(justify left bottom)
				(hide yes)
			)
		)
		(property "Footprint" "antmicro-footprints:LED_0603_1608Metric_G"
			(at 378.46 105.41 0)
			(effects
				(font
					(size 1.27 1.27)
					(thickness 0.15)
				)
				(justify left bottom)
				(hide yes)
			)
		)
		(property "Datasheet" "http://www.kingbright.com/attachments/file/psearch//000/00/00/KP-1608CGCK(Ver.23B).pdf"
			(at 375.92 105.41 0)
			(effects
				(font
					(size 1.27 1.27)
					(thickness 0.15)
				)
				(justify left bottom)
				(hide yes)
			)
		)
		(property "Description" ""
			(at 388.62 128.27 0)
			(effects
				(font
					(size 1.27 1.27)
				)
				(hide yes)
			)
		)
		(property "MPN" "KP-1608CGCK"
			(at 373.38 105.41 0)
			(effects
				(font
					(size 1.27 1.27)
					(thickness 0.15)
				)
				(justify left bottom)
				(hide yes)
			)
		)
		(property "Manufacturer" "Kingbright"
			(at 370.84 105.41 0)
			(effects
				(font
					(size 1.27 1.27)
					(thickness 0.15)
				)
				(justify left bottom)
				(hide yes)
			)
		)
		(property "Color" "Green"
			(at 394.97 127 90)
			(effects
				(font
					(size 1.27 1.27)
				)
			)
		)
		(property "Author" "Antmicro"
			(at 368.3 105.41 0)
			(effects
				(font
					(size 1.27 1.27)
					(thickness 0.15)
				)
				(justify left bottom)
				(hide yes)
			)
		)
		(property "License" "Apache-2.0"
			(at 365.76 105.41 0)
			(effects
				(font
					(size 1.27 1.27)
					(thickness 0.15)
				)
				(justify left bottom)
				(hide yes)
			)
		)
		(pin "2"
		)
		(pin "1"
		)
		(instances
			(project "cm4-baseboard"
				(path ""
					(reference "D304")
					(unit 1)
				)
			)
		)
	)
	(symbol
		(lib_id "antmicropower:PWR_FLAG")
		(at 62.23 207.01 0)
		(unit 1)
		(exclude_from_sim no)
		(in_bom yes)
		(on_board yes)
		(dnp no)
		(property "Reference" "#FLG03"
			(at 62.23 205.105 0)
			(effects
				(font
					(size 1.27 1.27)
				)
				(hide yes)
			)
		)
		(property "Value" "PWR_FLAG"
			(at 62.23 203.2 0)
			(effects
				(font
					(size 1.27 1.27)
				)
			)
		)
		(property "Footprint" ""
			(at 62.23 207.01 0)
			(effects
				(font
					(size 1.27 1.27)
				)
				(hide yes)
			)
		)
		(property "Datasheet" ""
			(at 62.23 207.01 0)
			(effects
				(font
					(size 1.27 1.27)
				)
				(hide yes)
			)
		)
		(property "Description" ""
			(at 62.23 207.01 0)
			(effects
				(font
					(size 1.27 1.27)
				)
				(hide yes)
			)
		)
		(pin "1"
		)
		(instances
			(project "cm4-baseboard"
				(path ""
					(reference "#FLG03")
					(unit 1)
				)
			)
		)
	)
	(symbol
		(lib_id "antmicropower:GND")
		(at 193.04 144.78 0)
		(mirror y)
		(unit 1)
		(exclude_from_sim no)
		(in_bom yes)
		(on_board yes)
		(dnp no)
		(fields_autoplaced yes)
		(property "Reference" "#PWR0313"
			(at 193.04 151.13 0)
			(effects
				(font
					(size 1.27 1.27)
				)
				(justify left bottom)
				(hide yes)
			)
		)
		(property "Value" "GND"
			(at 193.04 149.86 0)
			(effects
				(font
					(size 1.27 1.27)
				)
			)
		)
		(property "Footprint" ""
			(at 184.15 152.4 0)
			(effects
				(font
					(size 1.27 1.27)
					(thickness 0.15)
				)
				(justify left bottom)
				(hide yes)
			)
		)
		(property "Datasheet" ""
			(at 184.15 157.48 0)
			(effects
				(font
					(size 1.27 1.27)
					(thickness 0.15)
				)
				(justify left bottom)
				(hide yes)
			)
		)
		(property "Description" ""
			(at 193.04 144.78 0)
			(effects
				(font
					(size 1.27 1.27)
				)
				(hide yes)
			)
		)
		(property "Author" "Antmicro"
			(at 184.15 152.4 0)
			(effects
				(font
					(size 1.27 1.27)
					(thickness 0.15)
				)
				(justify left bottom)
				(hide yes)
			)
		)
		(property "License" "Apache-2.0"
			(at 184.15 154.94 0)
			(effects
				(font
					(size 1.27 1.27)
					(thickness 0.15)
				)
				(justify left bottom)
				(hide yes)
			)
		)
		(pin "1"
		)
		(instances
			(project "cm4-baseboard"
				(path ""
					(reference "#PWR0313")
					(unit 1)
				)
			)
		)
	)
	(symbol
		(lib_id "antmicropower:GND")
		(at 87.63 238.76 0)
		(unit 1)
		(exclude_from_sim no)
		(in_bom yes)
		(on_board yes)
		(dnp no)
		(property "Reference" "#PWR0308"
			(at 87.63 245.11 0)
			(effects
				(font
					(size 1.27 1.27)
				)
				(justify left bottom)
				(hide yes)
			)
		)
		(property "Value" "GND"
			(at 89.535 242.57 0)
			(effects
				(font
					(size 1.27 1.27)
				)
				(justify right)
			)
		)
		(property "Footprint" ""
			(at 96.52 246.38 0)
			(effects
				(font
					(size 1.27 1.27)
					(thickness 0.15)
				)
				(justify left bottom)
				(hide yes)
			)
		)
		(property "Datasheet" ""
			(at 96.52 251.46 0)
			(effects
				(font
					(size 1.27 1.27)
					(thickness 0.15)
				)
				(justify left bottom)
				(hide yes)
			)
		)
		(property "Description" ""
			(at 87.63 238.76 0)
			(effects
				(font
					(size 1.27 1.27)
				)
				(hide yes)
			)
		)
		(property "Author" "Antmicro"
			(at 96.52 246.38 0)
			(effects
				(font
					(size 1.27 1.27)
					(thickness 0.15)
				)
				(justify left bottom)
				(hide yes)
			)
		)
		(property "License" "Apache-2.0"
			(at 96.52 248.92 0)
			(effects
				(font
					(size 1.27 1.27)
					(thickness 0.15)
				)
				(justify left bottom)
				(hide yes)
			)
		)
		(pin "1"
		)
		(instances
			(project "cm4-baseboard"
				(path ""
					(reference "#PWR0308")
					(unit 1)
				)
			)
		)
	)
	(symbol
		(lib_id "antmicroPMICORControllersIdealDiodes:DZDH0401DW")
		(at 67.31 138.43 0)
		(unit 1)
		(exclude_from_sim no)
		(in_bom yes)
		(on_board yes)
		(dnp no)
		(fields_autoplaced yes)
		(property "Reference" "Q301"
			(at 75.565 132.08 0)
			(effects
				(font
					(size 1.27 1.27)
					(thickness 0.15)
				)
			)
		)
		(property "Value" "DZDH0401DW"
			(at 75.565 134.62 0)
			(effects
				(font
					(size 1.27 1.27)
					(thickness 0.15)
				)
				(hide yes)
			)
		)
		(property "Footprint" "antmicro-footprints:SOT-363"
			(at 97.79 148.59 0)
			(effects
				(font
					(size 1.27 1.27)
					(thickness 0.15)
				)
				(justify left bottom)
				(hide yes)
			)
		)
		(property "Datasheet" "https://www.mouser.com/datasheet/2/115/DIOD_S_A0011803041_1-2543705.pdf"
			(at 97.79 151.13 0)
			(effects
				(font
					(size 1.27 1.27)
					(thickness 0.15)
				)
				(justify left bottom)
				(hide yes)
			)
		)
		(property "Description" ""
			(at 67.31 138.43 0)
			(effects
				(font
					(size 1.27 1.27)
				)
				(hide yes)
			)
		)
		(property "MPN" "DZDH0401DW"
			(at 75.565 134.62 0)
			(effects
				(font
					(size 1.27 1.27)
					(thickness 0.15)
				)
			)
		)
		(property "Manufacturer" "Diodes Incorporated"
			(at 97.79 156.21 0)
			(effects
				(font
					(size 1.27 1.27)
					(thickness 0.15)
				)
				(justify left bottom)
				(hide yes)
			)
		)
		(property "Author" "Antmicro"
			(at 97.79 158.75 0)
			(effects
				(font
					(size 1.27 1.27)
					(thickness 0.15)
				)
				(justify left bottom)
				(hide yes)
			)
		)
		(property "License" "Apache-2.0"
			(at 97.79 161.29 0)
			(effects
				(font
					(size 1.27 1.27)
					(thickness 0.15)
				)
				(justify left bottom)
				(hide yes)
			)
		)
		(pin "4"
		)
		(pin "6"
		)
		(pin "2"
		)
		(pin "3"
		)
		(pin "1"
		)
		(pin "5"
		)
		(instances
			(project "cm4-baseboard"
				(path ""
					(reference "Q301")
					(unit 1)
				)
			)
		)
	)
	(symbol
		(lib_id "antmicroResistors0402:R_10k_0402")
		(at 279.4 226.06 270)
		(mirror x)
		(unit 1)
		(exclude_from_sim no)
		(in_bom yes)
		(on_board yes)
		(dnp no)
		(property "Reference" "R311"
			(at 278.13 222.25 90)
			(effects
				(font
					(size 1.27 1.27)
					(thickness 0.15)
				)
				(justify right)
			)
		)
		(property "Value" "R_10k_0402"
			(at 266.7 205.74 0)
			(effects
				(font
					(size 1.27 1.27)
					(thickness 0.15)
				)
				(justify left bottom)
				(hide yes)
			)
		)
		(property "Footprint" "antmicro-footprints:R_0402_1005Metric"
			(at 264.16 205.74 0)
			(effects
				(font
					(size 1.27 1.27)
					(thickness 0.15)
				)
				(justify left bottom)
				(hide yes)
			)
		)
		(property "Datasheet" "https://www.bourns.com/docs/product-datasheets/cr.pdf"
			(at 261.62 205.74 0)
			(effects
				(font
					(size 1.27 1.27)
					(thickness 0.15)
				)
				(justify left bottom)
				(hide yes)
			)
		)
		(property "Description" ""
			(at 279.4 226.06 0)
			(effects
				(font
					(size 1.27 1.27)
				)
				(hide yes)
			)
		)
		(property "Manufacturer" "Bourns"
			(at 256.54 205.74 0)
			(effects
				(font
					(size 1.27 1.27)
					(thickness 0.15)
				)
				(justify left bottom)
				(hide yes)
			)
		)
		(property "MPN" "CR0402-FX-1002GLF"
			(at 259.08 205.74 0)
			(effects
				(font
					(size 1.27 1.27)
					(thickness 0.15)
				)
				(justify left bottom)
				(hide yes)
			)
		)
		(property "Val" "10k"
			(at 278.13 224.79 90)
			(effects
				(font
					(size 1.27 1.27)
					(thickness 0.15)
				)
				(justify right)
			)
		)
		(property "License" "Apache-2.0"
			(at 254 205.74 0)
			(effects
				(font
					(size 1.27 1.27)
					(thickness 0.15)
				)
				(justify left bottom)
				(hide yes)
			)
		)
		(property "Author" "Antmicro"
			(at 251.46 205.74 0)
			(effects
				(font
					(size 1.27 1.27)
					(thickness 0.15)
				)
				(justify left bottom)
				(hide yes)
			)
		)
		(property "Tolerance" "1%"
			(at 269.24 205.74 0)
			(effects
				(font
					(size 1.27 1.27)
				)
				(justify left bottom)
				(hide yes)
			)
		)
		(pin "1"
		)
		(pin "2"
		)
		(instances
			(project "cm4-baseboard"
				(path ""
					(reference "R311")
					(unit 1)
				)
			)
		)
	)
	(symbol
		(lib_id "antmicroResistors0402:R_470k_0402")
		(at 87.63 148.59 90)
		(unit 1)
		(exclude_from_sim no)
		(in_bom yes)
		(on_board yes)
		(dnp no)
		(property "Reference" "R304"
			(at 88.9 144.78 90)
			(effects
				(font
					(size 1.27 1.27)
					(thickness 0.15)
				)
				(justify right)
			)
		)
		(property "Value" "R_470k_0402"
			(at 100.33 128.27 0)
			(effects
				(font
					(size 1.27 1.27)
					(thickness 0.15)
				)
				(justify left bottom)
				(hide yes)
			)
		)
		(property "Footprint" "antmicro-footprints:R_0402_1005Metric"
			(at 102.87 128.27 0)
			(effects
				(font
					(size 1.27 1.27)
					(thickness 0.15)
				)
				(justify left bottom)
				(hide yes)
			)
		)
		(property "Datasheet" "https://www.bourns.com/docs/product-datasheets/cr.pdf"
			(at 105.41 128.27 0)
			(effects
				(font
					(size 1.27 1.27)
					(thickness 0.15)
				)
				(justify left bottom)
				(hide yes)
			)
		)
		(property "Description" ""
			(at 87.63 148.59 0)
			(effects
				(font
					(size 1.27 1.27)
				)
				(hide yes)
			)
		)
		(property "MPN" "CR0402-FX-4703GLF"
			(at 107.95 128.27 0)
			(effects
				(font
					(size 1.27 1.27)
					(thickness 0.15)
				)
				(justify left bottom)
				(hide yes)
			)
		)
		(property "Manufacturer" "Bourns"
			(at 110.49 128.27 0)
			(effects
				(font
					(size 1.27 1.27)
					(thickness 0.15)
				)
				(justify left bottom)
				(hide yes)
			)
		)
		(property "License" "Apache-2.0"
			(at 113.03 128.27 0)
			(effects
				(font
					(size 1.27 1.27)
					(thickness 0.15)
				)
				(justify left bottom)
				(hide yes)
			)
		)
		(property "Author" "Antmicro"
			(at 115.57 128.27 0)
			(effects
				(font
					(size 1.27 1.27)
					(thickness 0.15)
				)
				(justify left bottom)
				(hide yes)
			)
		)
		(property "Val" "470k"
			(at 88.9 147.32 90)
			(effects
				(font
					(size 1.27 1.27)
					(thickness 0.15)
				)
				(justify right)
			)
		)
		(property "Tolerance" "1%"
			(at 97.79 128.27 0)
			(effects
				(font
					(size 1.27 1.27)
				)
				(justify left bottom)
				(hide yes)
			)
		)
		(pin "1"
		)
		(pin "2"
		)
		(instances
			(project "cm4-baseboard"
				(path ""
					(reference "R304")
					(unit 1)
				)
			)
		)
	)
	(symbol
		(lib_id "antmicroResistors0402:R_470R_0402")
		(at 388.62 184.15 270)
		(mirror x)
		(unit 1)
		(exclude_from_sim no)
		(in_bom yes)
		(on_board yes)
		(dnp no)
		(fields_autoplaced yes)
		(property "Reference" "R326"
			(at 391.16 180.3399 90)
			(effects
				(font
					(size 1.27 1.27)
				)
				(justify left)
			)
		)
		(property "Value" "R_470R_0402"
			(at 375.92 163.83 0)
			(effects
				(font
					(size 1.27 1.27)
					(thickness 0.15)
				)
				(justify left bottom)
				(hide yes)
			)
		)
		(property "Footprint" "antmicro-footprints:R_0402_1005Metric"
			(at 373.38 163.83 0)
			(effects
				(font
					(size 1.27 1.27)
					(thickness 0.15)
				)
				(justify left bottom)
				(hide yes)
			)
		)
		(property "Datasheet" "https://www.bourns.com/docs/product-datasheets/cr.pdf"
			(at 370.84 163.83 0)
			(effects
				(font
					(size 1.27 1.27)
					(thickness 0.15)
				)
				(justify left bottom)
				(hide yes)
			)
		)
		(property "Description" ""
			(at 388.62 184.15 0)
			(effects
				(font
					(size 1.27 1.27)
				)
				(hide yes)
			)
		)
		(property "Manufacturer" "Bourns"
			(at 365.76 163.83 0)
			(effects
				(font
					(size 1.27 1.27)
					(thickness 0.15)
				)
				(justify left bottom)
				(hide yes)
			)
		)
		(property "MPN" "CR0402-FX-4700GLF"
			(at 368.3 163.83 0)
			(effects
				(font
					(size 1.27 1.27)
					(thickness 0.15)
				)
				(justify left bottom)
				(hide yes)
			)
		)
		(property "Val" "470R"
			(at 391.16 182.8799 90)
			(effects
				(font
					(size 1.27 1.27)
					(thickness 0.15)
				)
				(justify left)
			)
		)
		(property "License" "Apache-2.0"
			(at 363.22 163.83 0)
			(effects
				(font
					(size 1.27 1.27)
					(thickness 0.15)
				)
				(justify left bottom)
				(hide yes)
			)
		)
		(property "Author" "Antmicro"
			(at 360.68 163.83 0)
			(effects
				(font
					(size 1.27 1.27)
					(thickness 0.15)
				)
				(justify left bottom)
				(hide yes)
			)
		)
		(property "Tolerance" "1%"
			(at 378.46 163.83 0)
			(effects
				(font
					(size 1.27 1.27)
				)
				(justify left bottom)
				(hide yes)
			)
		)
		(pin "1"
		)
		(pin "2"
		)
		(instances
			(project "cm4-baseboard"
				(path ""
					(reference "R326")
					(unit 1)
				)
			)
		)
	)
	(symbol
		(lib_id "antmicroResistors0402:R_4k7_0402")
		(at 147.32 142.24 90)
		(unit 1)
		(exclude_from_sim no)
		(in_bom yes)
		(on_board yes)
		(dnp no)
		(property "Reference" "R309"
			(at 148.59 138.43 90)
			(effects
				(font
					(size 1.27 1.27)
				)
				(justify right)
			)
		)
		(property "Value" "R_4k7_0402"
			(at 151.13 142.24 0)
			(effects
				(font
					(size 1.27 1.27)
				)
				(justify left bottom)
				(hide yes)
			)
		)
		(property "Footprint" "antmicro-footprints:R_0402_1005Metric"
			(at 142.24 137.16 0)
			(effects
				(font
					(size 1.524 1.524)
				)
				(justify left bottom)
				(hide yes)
			)
		)
		(property "Datasheet" "https://www.bourns.com/docs/product-datasheets/cr.pdf"
			(at 147.32 142.24 0)
			(effects
				(font
					(size 1.27 1.27)
				)
				(justify left bottom)
				(hide yes)
			)
		)
		(property "Description" ""
			(at 147.32 142.24 0)
			(effects
				(font
					(size 1.27 1.27)
				)
				(hide yes)
			)
		)
		(property "Manufacturer" "Bourns"
			(at 137.16 137.16 0)
			(effects
				(font
					(size 1.524 1.524)
				)
				(justify left bottom)
				(hide yes)
			)
		)
		(property "MPN" "CR0402-FX-4701GLF"
			(at 139.7 137.16 0)
			(effects
				(font
					(size 1.524 1.524)
				)
				(justify left bottom)
				(hide yes)
			)
		)
		(property "Val" "4k7"
			(at 148.59 140.97 90)
			(effects
				(font
					(size 1.27 1.27)
				)
				(justify right)
			)
		)
		(property "License" "Apache-2.0"
			(at 172.72 121.92 0)
			(effects
				(font
					(size 1.27 1.27)
					(thickness 0.15)
				)
				(justify left bottom)
				(hide yes)
			)
		)
		(property "Author" "Antmicro"
			(at 175.26 121.92 0)
			(effects
				(font
					(size 1.27 1.27)
					(thickness 0.15)
				)
				(justify left bottom)
				(hide yes)
			)
		)
		(property "Tolerance" "1%"
			(at 157.48 121.92 0)
			(effects
				(font
					(size 1.27 1.27)
				)
				(justify left bottom)
				(hide yes)
			)
		)
		(pin "1"
		)
		(pin "2"
		)
		(instances
			(project "cm4-baseboard"
				(path ""
					(reference "R309")
					(unit 1)
				)
			)
		)
	)
	(symbol
		(lib_id "antmicropower:GND")
		(at 335.28 137.16 0)
		(unit 1)
		(exclude_from_sim no)
		(in_bom yes)
		(on_board yes)
		(dnp no)
		(property "Reference" "#PWR0329"
			(at 335.28 143.51 0)
			(effects
				(font
					(size 1.27 1.27)
				)
				(justify left bottom)
				(hide yes)
			)
		)
		(property "Value" "GND"
			(at 335.28 140.97 0)
			(effects
				(font
					(size 1.27 1.27)
				)
			)
		)
		(property "Footprint" ""
			(at 344.17 144.78 0)
			(effects
				(font
					(size 1.27 1.27)
					(thickness 0.15)
				)
				(justify left bottom)
				(hide yes)
			)
		)
		(property "Datasheet" ""
			(at 344.17 149.86 0)
			(effects
				(font
					(size 1.27 1.27)
					(thickness 0.15)
				)
				(justify left bottom)
				(hide yes)
			)
		)
		(property "Description" ""
			(at 335.28 137.16 0)
			(effects
				(font
					(size 1.27 1.27)
				)
				(hide yes)
			)
		)
		(property "Author" "Antmicro"
			(at 344.17 144.78 0)
			(effects
				(font
					(size 1.27 1.27)
					(thickness 0.15)
				)
				(justify left bottom)
				(hide yes)
			)
		)
		(property "License" "Apache-2.0"
			(at 344.17 147.32 0)
			(effects
				(font
					(size 1.27 1.27)
					(thickness 0.15)
				)
				(justify left bottom)
				(hide yes)
			)
		)
		(pin "1"
		)
		(instances
			(project "cm4-baseboard"
				(path ""
					(reference "#PWR0329")
					(unit 1)
				)
			)
		)
	)
	(symbol
		(lib_id "antmicroResistors0402:R_33k_0402")
		(at 66.04 237.49 90)
		(unit 1)
		(exclude_from_sim no)
		(in_bom yes)
		(on_board yes)
		(dnp no)
		(property "Reference" "R303"
			(at 67.31 233.68 90)
			(effects
				(font
					(size 1.27 1.27)
					(thickness 0.15)
				)
				(justify right)
			)
		)
		(property "Value" "R_33k_0402"
			(at 78.74 217.17 0)
			(effects
				(font
					(size 1.27 1.27)
					(thickness 0.15)
				)
				(justify left bottom)
				(hide yes)
			)
		)
		(property "Footprint" "antmicro-footprints:R_0402_1005Metric"
			(at 81.28 217.17 0)
			(effects
				(font
					(size 1.27 1.27)
					(thickness 0.15)
				)
				(justify left bottom)
				(hide yes)
			)
		)
		(property "Datasheet" "https://www.bourns.com/docs/product-datasheets/cr.pdf"
			(at 83.82 217.17 0)
			(effects
				(font
					(size 1.27 1.27)
					(thickness 0.15)
				)
				(justify left bottom)
				(hide yes)
			)
		)
		(property "Description" ""
			(at 66.04 237.49 0)
			(effects
				(font
					(size 1.27 1.27)
				)
				(hide yes)
			)
		)
		(property "MPN" "CR0402-FX-3302GLF"
			(at 86.36 217.17 0)
			(effects
				(font
					(size 1.27 1.27)
					(thickness 0.15)
				)
				(justify left bottom)
				(hide yes)
			)
		)
		(property "Manufacturer" "Bourns"
			(at 88.9 217.17 0)
			(effects
				(font
					(size 1.27 1.27)
					(thickness 0.15)
				)
				(justify left bottom)
				(hide yes)
			)
		)
		(property "License" "Apache-2.0"
			(at 91.44 217.17 0)
			(effects
				(font
					(size 1.27 1.27)
					(thickness 0.15)
				)
				(justify left bottom)
				(hide yes)
			)
		)
		(property "Author" "Antmicro"
			(at 93.98 217.17 0)
			(effects
				(font
					(size 1.27 1.27)
					(thickness 0.15)
				)
				(justify left bottom)
				(hide yes)
			)
		)
		(property "Val" "33k"
			(at 67.31 236.22 90)
			(effects
				(font
					(size 1.27 1.27)
					(thickness 0.15)
				)
				(justify right)
			)
		)
		(property "Tolerance" "1%"
			(at 76.2 217.17 0)
			(effects
				(font
					(size 1.27 1.27)
				)
				(justify left bottom)
				(hide yes)
			)
		)
		(pin "2"
		)
		(pin "1"
		)
		(instances
			(project "cm4-baseboard"
				(path ""
					(reference "R303")
					(unit 1)
				)
			)
		)
	)
	(symbol
		(lib_id "antmicropower:GND")
		(at 289.56 194.31 0)
		(unit 1)
		(exclude_from_sim no)
		(in_bom yes)
		(on_board yes)
		(dnp no)
		(fields_autoplaced yes)
		(property "Reference" "#PWR0324"
			(at 298.45 196.85 0)
			(effects
				(font
					(size 1.27 1.27)
					(thickness 0.15)
				)
				(justify left bottom)
				(hide yes)
			)
		)
		(property "Value" "GND"
			(at 287.5498 199.39 0)
			(effects
				(font
					(size 1.27 1.27)
					(thickness 0.15)
				)
				(justify left bottom)
			)
		)
		(property "Footprint" ""
			(at 298.45 201.93 0)
			(effects
				(font
					(size 1.27 1.27)
					(thickness 0.15)
				)
				(justify left bottom)
				(hide yes)
			)
		)
		(property "Datasheet" ""
			(at 298.45 207.01 0)
			(effects
				(font
					(size 1.27 1.27)
					(thickness 0.15)
				)
				(justify left bottom)
				(hide yes)
			)
		)
		(property "Description" ""
			(at 289.56 194.31 0)
			(effects
				(font
					(size 1.27 1.27)
				)
				(hide yes)
			)
		)
		(property "Author" "Antmicro"
			(at 298.45 201.93 0)
			(effects
				(font
					(size 1.27 1.27)
					(thickness 0.15)
				)
				(justify left bottom)
				(hide yes)
			)
		)
		(property "License" "Apache-2.0"
			(at 298.45 204.47 0)
			(effects
				(font
					(size 1.27 1.27)
					(thickness 0.15)
				)
				(justify left bottom)
				(hide yes)
			)
		)
		(pin "1"
		)
		(instances
			(project "cm4-baseboard"
				(path ""
					(reference "#PWR0324")
					(unit 1)
				)
			)
		)
	)
	(symbol
		(lib_id "antmicroWire2BoardConnectors:Molex_Nano-Fit_1x2_SMD_1054301202")
		(at 33.02 121.92 0)
		(mirror y)
		(unit 1)
		(exclude_from_sim no)
		(in_bom yes)
		(on_board yes)
		(dnp no)
		(property "Reference" "J301"
			(at 27.94 115.57 0)
			(effects
				(font
					(size 1.27 1.27)
				)
			)
		)
		(property "Value" "Molex_Nano-Fit_1x2_SMD_1054301202"
			(at 33.02 132.08 0)
			(effects
				(font
					(size 1.27 1.27)
				)
				(justify left bottom)
				(hide yes)
			)
		)
		(property "Footprint" "antmicro-footprints:Conn_Molex_Nano-Fit_1x2_SMD_1054301202"
			(at 33.02 134.62 0)
			(effects
				(font
					(size 1.27 1.27)
				)
				(justify left bottom)
				(hide yes)
			)
		)
		(property "Datasheet" "https://www.farnell.com/cad/3578051.pdf"
			(at 33.02 137.16 0)
			(effects
				(font
					(size 1.27 1.27)
				)
				(justify left bottom)
				(hide yes)
			)
		)
		(property "Description" ""
			(at 33.02 121.92 0)
			(effects
				(font
					(size 1.27 1.27)
				)
				(hide yes)
			)
		)
		(property "Manufacturer" "Molex"
			(at 33.02 142.24 0)
			(effects
				(font
					(size 1.27 1.27)
				)
				(justify left bottom)
				(hide yes)
			)
		)
		(property "MPN" "105430-1202"
			(at 35.56 118.11 0)
			(effects
				(font
					(size 1.27 1.27)
				)
				(justify left bottom)
			)
		)
		(property "Author" "Antmicro"
			(at 12.7 147.32 0)
			(effects
				(font
					(size 1.27 1.27)
					(thickness 0.15)
				)
				(justify left bottom)
				(hide yes)
			)
		)
		(property "License" "Apache-2.0"
			(at 12.7 149.86 0)
			(effects
				(font
					(size 1.27 1.27)
					(thickness 0.15)
				)
				(justify left bottom)
				(hide yes)
			)
		)
		(pin "1"
		)
		(pin "2"
		)
		(pin "MP"
		)
		(instances
			(project "cm4-baseboard"
				(path ""
					(reference "J301")
					(unit 1)
				)
			)
		)
	)
	(symbol
		(lib_id "antmicropower:GND")
		(at 323.85 137.16 0)
		(unit 1)
		(exclude_from_sim no)
		(in_bom yes)
		(on_board yes)
		(dnp no)
		(property "Reference" "#PWR0328"
			(at 323.85 143.51 0)
			(effects
				(font
					(size 1.27 1.27)
				)
				(justify left bottom)
				(hide yes)
			)
		)
		(property "Value" "GND"
			(at 323.85 140.97 0)
			(effects
				(font
					(size 1.27 1.27)
				)
			)
		)
		(property "Footprint" ""
			(at 332.74 144.78 0)
			(effects
				(font
					(size 1.27 1.27)
					(thickness 0.15)
				)
				(justify left bottom)
				(hide yes)
			)
		)
		(property "Datasheet" ""
			(at 332.74 149.86 0)
			(effects
				(font
					(size 1.27 1.27)
					(thickness 0.15)
				)
				(justify left bottom)
				(hide yes)
			)
		)
		(property "Description" ""
			(at 323.85 137.16 0)
			(effects
				(font
					(size 1.27 1.27)
				)
				(hide yes)
			)
		)
		(property "Author" "Antmicro"
			(at 332.74 144.78 0)
			(effects
				(font
					(size 1.27 1.27)
					(thickness 0.15)
				)
				(justify left bottom)
				(hide yes)
			)
		)
		(property "License" "Apache-2.0"
			(at 332.74 147.32 0)
			(effects
				(font
					(size 1.27 1.27)
					(thickness 0.15)
				)
				(justify left bottom)
				(hide yes)
			)
		)
		(pin "1"
		)
		(instances
			(project "cm4-baseboard"
				(path ""
					(reference "#PWR0328")
					(unit 1)
				)
			)
		)
	)
	(symbol
		(lib_id "antmicroFixedInductors:L_1u_5.5A_Bourns-SRP3212A")
		(at 323.85 175.26 0)
		(unit 1)
		(exclude_from_sim no)
		(in_bom yes)
		(on_board yes)
		(dnp no)
		(fields_autoplaced yes)
		(property "Reference" "L301"
			(at 326.39 170.18 0)
			(effects
				(font
					(size 1.27 1.27)
					(thickness 0.15)
				)
			)
		)
		(property "Value" "L_1u_5.5A_Bourns-SRP3212A"
			(at 326.39 170.18 0)
			(effects
				(font
					(size 1.27 1.27)
					(thickness 0.15)
				)
				(hide yes)
			)
		)
		(property "Footprint" "antmicro-footprints:L_Bourns-SRP3212A"
			(at 337.82 182.88 0)
			(effects
				(font
					(size 1.27 1.27)
					(thickness 0.15)
				)
				(justify left bottom)
				(hide yes)
			)
		)
		(property "Datasheet" "https://www.mouser.com/datasheet/2/54/SRP3212A-3011944.pdf"
			(at 337.82 185.42 0)
			(effects
				(font
					(size 1.27 1.27)
					(thickness 0.15)
				)
				(justify left bottom)
				(hide yes)
			)
		)
		(property "Description" ""
			(at 323.85 175.26 0)
			(effects
				(font
					(size 1.27 1.27)
				)
				(hide yes)
			)
		)
		(property "Manufacturer" "Bourns"
			(at 337.82 187.96 0)
			(effects
				(font
					(size 1.27 1.27)
					(thickness 0.15)
				)
				(justify left bottom)
				(hide yes)
			)
		)
		(property "MPN" "SRP3212A-1R0M"
			(at 337.82 190.5 0)
			(effects
				(font
					(size 1.27 1.27)
					(thickness 0.15)
				)
				(justify left bottom)
				(hide yes)
			)
		)
		(property "Size" "3.2x2.5"
			(at 337.82 198.12 0)
			(effects
				(font
					(size 1.27 1.27)
					(thickness 0.15)
				)
				(justify left bottom)
				(hide yes)
			)
		)
		(property "Val" "1u/5.5A"
			(at 326.39 172.72 0)
			(effects
				(font
					(size 1.27 1.27)
					(thickness 0.15)
				)
			)
		)
		(property "Author" "Antmicro"
			(at 337.82 200.66 0)
			(effects
				(font
					(size 1.27 1.27)
					(thickness 0.15)
				)
				(justify left bottom)
				(hide yes)
			)
		)
		(property "License" "Apache-2.0"
			(at 337.82 203.2 0)
			(effects
				(font
					(size 1.27 1.27)
					(thickness 0.15)
				)
				(justify left bottom)
				(hide yes)
			)
		)
		(property "ISat" "6.5 A"
			(at 337.82 191.77 0)
			(effects
				(font
					(size 1.27 1.27)
				)
				(justify left)
				(hide yes)
			)
		)
		(property "IMax" "5.5 A"
			(at 337.82 195.58 0)
			(effects
				(font
					(size 1.27 1.27)
					(thickness 0.15)
				)
				(justify left bottom)
				(hide yes)
			)
		)
		(pin "1"
		)
		(pin "2"
		)
		(instances
			(project "cm4-baseboard"
				(path ""
					(reference "L301")
					(unit 1)
				)
			)
		)
	)
	(symbol
		(lib_id "antmicroTestPoints:TP_0.75mm_SMD")
		(at 43.18 120.65 90)
		(unit 1)
		(exclude_from_sim no)
		(in_bom no)
		(on_board yes)
		(dnp no)
		(fields_autoplaced yes)
		(property "Reference" "TP306"
			(at 45.085 117.4749 90)
			(effects
				(font
					(size 1.27 1.27)
				)
				(justify right)
			)
		)
		(property "Value" "TP_0.75mm_SMD"
			(at 45.72 120.65 0)
			(effects
				(font
					(size 1.27 1.27)
					(thickness 0.15)
				)
				(justify left bottom)
				(hide yes)
			)
		)
		(property "Footprint" "antmicro-footprints:TP_SMD_0.75mm"
			(at 38.1 115.57 0)
			(effects
				(font
					(size 1.27 1.27)
					(thickness 0.15)
				)
				(justify left bottom)
				(hide yes)
			)
		)
		(property "Datasheet" ""
			(at 35.56 115.57 0)
			(effects
				(font
					(size 1.27 1.27)
					(thickness 0.15)
				)
				(justify left bottom)
				(hide yes)
			)
		)
		(property "Description" ""
			(at 43.18 120.65 0)
			(effects
				(font
					(size 1.27 1.27)
				)
				(hide yes)
			)
		)
		(property "MPN" ""
			(at 43.18 120.65 0)
			(effects
				(font
					(size 1.27 1.27)
					(thickness 0.15)
				)
				(justify left bottom)
				(hide yes)
			)
		)
		(property "Manufacturer" ""
			(at 43.18 120.65 0)
			(effects
				(font
					(size 1.27 1.27)
					(thickness 0.15)
				)
				(justify left bottom)
				(hide yes)
			)
		)
		(property "Author" "Antmicro"
			(at 58.42 105.41 0)
			(effects
				(font
					(size 1.27 1.27)
					(thickness 0.15)
				)
				(justify left bottom)
				(hide yes)
			)
		)
		(property "License" "Apache-2.0"
			(at 60.96 105.41 0)
			(effects
				(font
					(size 1.27 1.27)
					(thickness 0.15)
				)
				(justify left bottom)
				(hide yes)
			)
		)
		(pin "1"
		)
		(instances
			(project "cm4-baseboard"
				(path ""
					(reference "TP306")
					(unit 1)
				)
			)
		)
	)
	(symbol
		(lib_id "antmicropower:GND")
		(at 66.04 149.86 0)
		(unit 1)
		(exclude_from_sim no)
		(in_bom yes)
		(on_board yes)
		(dnp no)
		(property "Reference" "#PWR0303"
			(at 66.04 156.21 0)
			(effects
				(font
					(size 1.27 1.27)
				)
				(justify left bottom)
				(hide yes)
			)
		)
		(property "Value" "GND"
			(at 67.945 153.67 0)
			(effects
				(font
					(size 1.27 1.27)
				)
				(justify right)
			)
		)
		(property "Footprint" ""
			(at 74.93 157.48 0)
			(effects
				(font
					(size 1.27 1.27)
					(thickness 0.15)
				)
				(justify left bottom)
				(hide yes)
			)
		)
		(property "Datasheet" ""
			(at 74.93 162.56 0)
			(effects
				(font
					(size 1.27 1.27)
					(thickness 0.15)
				)
				(justify left bottom)
				(hide yes)
			)
		)
		(property "Description" ""
			(at 66.04 149.86 0)
			(effects
				(font
					(size 1.27 1.27)
				)
				(hide yes)
			)
		)
		(property "Author" "Antmicro"
			(at 74.93 157.48 0)
			(effects
				(font
					(size 1.27 1.27)
					(thickness 0.15)
				)
				(justify left bottom)
				(hide yes)
			)
		)
		(property "License" "Apache-2.0"
			(at 74.93 160.02 0)
			(effects
				(font
					(size 1.27 1.27)
					(thickness 0.15)
				)
				(justify left bottom)
				(hide yes)
			)
		)
		(pin "1"
		)
		(instances
			(project "cm4-baseboard"
				(path ""
					(reference "#PWR0303")
					(unit 1)
				)
			)
		)
	)
	(symbol
		(lib_id "antmicropower:+5V")
		(at 388.62 114.3 0)
		(unit 1)
		(exclude_from_sim no)
		(in_bom yes)
		(on_board yes)
		(dnp no)
		(fields_autoplaced yes)
		(property "Reference" "#PWR0341"
			(at 388.62 118.11 0)
			(effects
				(font
					(size 1.27 1.27)
				)
				(justify left bottom)
				(hide yes)
			)
		)
		(property "Value" "+5V"
			(at 388.62 108.585 0)
			(effects
				(font
					(size 1.27 1.27)
				)
			)
		)
		(property "Footprint" ""
			(at 403.86 121.92 0)
			(effects
				(font
					(size 1.27 1.27)
					(thickness 0.15)
				)
				(justify left bottom)
				(hide yes)
			)
		)
		(property "Datasheet" ""
			(at 403.86 124.46 0)
			(effects
				(font
					(size 1.27 1.27)
					(thickness 0.15)
				)
				(justify left bottom)
				(hide yes)
			)
		)
		(property "Description" ""
			(at 388.62 114.3 0)
			(effects
				(font
					(size 1.27 1.27)
				)
				(hide yes)
			)
		)
		(property "Author" "Antmicro"
			(at 403.86 121.92 0)
			(effects
				(font
					(size 1.27 1.27)
					(thickness 0.15)
				)
				(justify left bottom)
				(hide yes)
			)
		)
		(property "License" "Apache-2.0"
			(at 403.86 124.46 0)
			(effects
				(font
					(size 1.27 1.27)
					(thickness 0.15)
				)
				(justify left bottom)
				(hide yes)
			)
		)
		(pin "1"
		)
		(instances
			(project "cm4-baseboard"
				(path ""
					(reference "#PWR0341")
					(unit 1)
				)
			)
		)
	)
	(symbol
		(lib_id "antmicropower:GND")
		(at 185.42 144.78 0)
		(mirror y)
		(unit 1)
		(exclude_from_sim no)
		(in_bom yes)
		(on_board yes)
		(dnp no)
		(fields_autoplaced yes)
		(property "Reference" "#PWR0312"
			(at 185.42 151.13 0)
			(effects
				(font
					(size 1.27 1.27)
				)
				(justify left bottom)
				(hide yes)
			)
		)
		(property "Value" "GND"
			(at 185.42 149.86 0)
			(effects
				(font
					(size 1.27 1.27)
				)
			)
		)
		(property "Footprint" ""
			(at 176.53 152.4 0)
			(effects
				(font
					(size 1.27 1.27)
					(thickness 0.15)
				)
				(justify left bottom)
				(hide yes)
			)
		)
		(property "Datasheet" ""
			(at 176.53 157.48 0)
			(effects
				(font
					(size 1.27 1.27)
					(thickness 0.15)
				)
				(justify left bottom)
				(hide yes)
			)
		)
		(property "Description" ""
			(at 185.42 144.78 0)
			(effects
				(font
					(size 1.27 1.27)
				)
				(hide yes)
			)
		)
		(property "Author" "Antmicro"
			(at 176.53 152.4 0)
			(effects
				(font
					(size 1.27 1.27)
					(thickness 0.15)
				)
				(justify left bottom)
				(hide yes)
			)
		)
		(property "License" "Apache-2.0"
			(at 176.53 154.94 0)
			(effects
				(font
					(size 1.27 1.27)
					(thickness 0.15)
				)
				(justify left bottom)
				(hide yes)
			)
		)
		(pin "1"
		)
		(instances
			(project "cm4-baseboard"
				(path ""
					(reference "#PWR0312")
					(unit 1)
				)
			)
		)
	)
	(symbol
		(lib_id "antmicropower:PWR_FLAG")
		(at 171.45 120.65 0)
		(unit 1)
		(exclude_from_sim no)
		(in_bom yes)
		(on_board yes)
		(dnp no)
		(property "Reference" "#FLG09"
			(at 171.45 118.745 0)
			(effects
				(font
					(size 1.27 1.27)
				)
				(hide yes)
			)
		)
		(property "Value" "PWR_FLAG"
			(at 171.45 116.84 0)
			(effects
				(font
					(size 1.27 1.27)
				)
			)
		)
		(property "Footprint" ""
			(at 171.45 120.65 0)
			(effects
				(font
					(size 1.27 1.27)
				)
				(hide yes)
			)
		)
		(property "Datasheet" ""
			(at 171.45 120.65 0)
			(effects
				(font
					(size 1.27 1.27)
				)
				(hide yes)
			)
		)
		(property "Description" ""
			(at 171.45 120.65 0)
			(effects
				(font
					(size 1.27 1.27)
				)
				(hide yes)
			)
		)
		(pin "1"
		)
		(instances
			(project "cm4-baseboard"
				(path ""
					(reference "#FLG09")
					(unit 1)
				)
			)
		)
	)
	(symbol
		(lib_id "antmicroPMICORControllersIdealDiodes:DZDH0401DW")
		(at 67.31 227.33 0)
		(unit 1)
		(exclude_from_sim no)
		(in_bom yes)
		(on_board yes)
		(dnp no)
		(fields_autoplaced yes)
		(property "Reference" "Q303"
			(at 75.565 220.98 0)
			(effects
				(font
					(size 1.27 1.27)
					(thickness 0.15)
				)
			)
		)
		(property "Value" "DZDH0401DW"
			(at 75.565 223.52 0)
			(effects
				(font
					(size 1.27 1.27)
					(thickness 0.15)
				)
				(hide yes)
			)
		)
		(property "Footprint" "antmicro-footprints:SOT-363"
			(at 97.79 237.49 0)
			(effects
				(font
					(size 1.27 1.27)
					(thickness 0.15)
				)
				(justify left bottom)
				(hide yes)
			)
		)
		(property "Datasheet" "https://www.mouser.com/datasheet/2/115/DIOD_S_A0011803041_1-2543705.pdf"
			(at 97.79 240.03 0)
			(effects
				(font
					(size 1.27 1.27)
					(thickness 0.15)
				)
				(justify left bottom)
				(hide yes)
			)
		)
		(property "Description" ""
			(at 67.31 227.33 0)
			(effects
				(font
					(size 1.27 1.27)
				)
				(hide yes)
			)
		)
		(property "MPN" "DZDH0401DW"
			(at 75.565 223.52 0)
			(effects
				(font
					(size 1.27 1.27)
					(thickness 0.15)
				)
			)
		)
		(property "Manufacturer" "Diodes Incorporated"
			(at 97.79 245.11 0)
			(effects
				(font
					(size 1.27 1.27)
					(thickness 0.15)
				)
				(justify left bottom)
				(hide yes)
			)
		)
		(property "Author" "Antmicro"
			(at 97.79 247.65 0)
			(effects
				(font
					(size 1.27 1.27)
					(thickness 0.15)
				)
				(justify left bottom)
				(hide yes)
			)
		)
		(property "License" "Apache-2.0"
			(at 97.79 250.19 0)
			(effects
				(font
					(size 1.27 1.27)
					(thickness 0.15)
				)
				(justify left bottom)
				(hide yes)
			)
		)
		(pin "4"
		)
		(pin "6"
		)
		(pin "2"
		)
		(pin "3"
		)
		(pin "1"
		)
		(pin "5"
		)
		(instances
			(project "cm4-baseboard"
				(path ""
					(reference "Q303")
					(unit 1)
				)
			)
		)
	)
	(symbol
		(lib_id "antmicroResistors0603:R_0R_22.4A_0603")
		(at 367.03 110.49 0)
		(unit 1)
		(exclude_from_sim no)
		(in_bom yes)
		(on_board yes)
		(dnp no)
		(property "Reference" "R324"
			(at 369.57 107.95 0)
			(effects
				(font
					(size 1.27 1.27)
				)
			)
		)
		(property "Value" "R_0R_22.4A_0603"
			(at 367.03 114.3 0)
			(effects
				(font
					(size 1.27 1.27)
				)
				(justify left bottom)
				(hide yes)
			)
		)
		(property "Footprint" "antmicro-footprints:R_0603_1608Metric"
			(at 372.11 105.41 0)
			(effects
				(font
					(size 1.524 1.524)
				)
				(justify left bottom)
				(hide yes)
			)
		)
		(property "Datasheet" "https://fscdn.rohm.com/en/products/databook/datasheet/passive/resistor/chip_resistor/pmr-jpw-e.pdf"
			(at 367.03 110.49 0)
			(effects
				(font
					(size 1.27 1.27)
				)
				(justify left bottom)
				(hide yes)
			)
		)
		(property "Description" ""
			(at 367.03 110.49 0)
			(effects
				(font
					(size 1.27 1.27)
				)
				(hide yes)
			)
		)
		(property "Manufacturer" "ROHM Semiconductor"
			(at 372.11 100.33 0)
			(effects
				(font
					(size 1.524 1.524)
				)
				(justify left bottom)
				(hide yes)
			)
		)
		(property "MPN" "PMR03EZPJ000"
			(at 372.11 102.87 0)
			(effects
				(font
					(size 1.524 1.524)
				)
				(justify left bottom)
				(hide yes)
			)
		)
		(property "Val" "0R"
			(at 369.57 110.49 0)
			(effects
				(font
					(size 1.27 1.27)
				)
			)
		)
		(property "Author" "Antmicro"
			(at 389.89 133.35 0)
			(effects
				(font
					(size 1.27 1.27)
					(thickness 0.15)
				)
				(justify left bottom)
				(hide yes)
			)
		)
		(property "License" "Apache-2.0"
			(at 389.89 135.89 0)
			(effects
				(font
					(size 1.27 1.27)
					(thickness 0.15)
				)
				(justify left bottom)
				(hide yes)
			)
		)
		(property "Max. Curr." "22.4A"
			(at 367.03 113.665 0)
			(effects
				(font
					(size 1.27 1.27)
					(thickness 0.15)
				)
				(justify left bottom)
			)
		)
		(property "Tolerance" "template_tolerance"
			(at 387.35 120.65 0)
			(effects
				(font
					(size 1.27 1.27)
				)
				(justify left bottom)
				(hide yes)
			)
		)
		(pin "1"
		)
		(pin "2"
		)
		(instances
			(project "cm4-baseboard"
				(path ""
					(reference "R324")
					(unit 1)
				)
			)
		)
	)
	(symbol
		(lib_id "antmicropower:GND")
		(at 66.04 238.76 0)
		(unit 1)
		(exclude_from_sim no)
		(in_bom yes)
		(on_board yes)
		(dnp no)
		(property "Reference" "#PWR0305"
			(at 66.04 245.11 0)
			(effects
				(font
					(size 1.27 1.27)
				)
				(justify left bottom)
				(hide yes)
			)
		)
		(property "Value" "GND"
			(at 67.945 242.57 0)
			(effects
				(font
					(size 1.27 1.27)
				)
				(justify right)
			)
		)
		(property "Footprint" ""
			(at 74.93 246.38 0)
			(effects
				(font
					(size 1.27 1.27)
					(thickness 0.15)
				)
				(justify left bottom)
				(hide yes)
			)
		)
		(property "Datasheet" ""
			(at 74.93 251.46 0)
			(effects
				(font
					(size 1.27 1.27)
					(thickness 0.15)
				)
				(justify left bottom)
				(hide yes)
			)
		)
		(property "Description" ""
			(at 66.04 238.76 0)
			(effects
				(font
					(size 1.27 1.27)
				)
				(hide yes)
			)
		)
		(property "Author" "Antmicro"
			(at 74.93 246.38 0)
			(effects
				(font
					(size 1.27 1.27)
					(thickness 0.15)
				)
				(justify left bottom)
				(hide yes)
			)
		)
		(property "License" "Apache-2.0"
			(at 74.93 248.92 0)
			(effects
				(font
					(size 1.27 1.27)
					(thickness 0.15)
				)
				(justify left bottom)
				(hide yes)
			)
		)
		(pin "1"
		)
		(instances
			(project "cm4-baseboard"
				(path ""
					(reference "#PWR0305")
					(unit 1)
				)
			)
		)
	)
	(symbol
		(lib_id "antmicroResistors0603:R_0R_22.4A_0603")
		(at 147.32 110.49 0)
		(unit 1)
		(exclude_from_sim no)
		(in_bom no)
		(on_board yes)
		(dnp yes)
		(property "Reference" "R308"
			(at 149.86 102.87 0)
			(effects
				(font
					(size 1.27 1.27)
				)
			)
		)
		(property "Value" "R_0R_22.4A_0603"
			(at 147.32 114.3 0)
			(effects
				(font
					(size 1.27 1.27)
				)
				(justify left bottom)
				(hide yes)
			)
		)
		(property "Footprint" "antmicro-footprints:R_0603_1608Metric"
			(at 152.4 105.41 0)
			(effects
				(font
					(size 1.524 1.524)
				)
				(justify left bottom)
				(hide yes)
			)
		)
		(property "Datasheet" "https://fscdn.rohm.com/en/products/databook/datasheet/passive/resistor/chip_resistor/pmr-jpw-e.pdf"
			(at 147.32 110.49 0)
			(effects
				(font
					(size 1.27 1.27)
				)
				(justify left bottom)
				(hide yes)
			)
		)
		(property "Description" ""
			(at 147.32 110.49 0)
			(effects
				(font
					(size 1.27 1.27)
				)
				(hide yes)
			)
		)
		(property "Manufacturer" "ROHM Semiconductor"
			(at 152.4 100.33 0)
			(effects
				(font
					(size 1.524 1.524)
				)
				(justify left bottom)
				(hide yes)
			)
		)
		(property "MPN" "PMR03EZPJ000"
			(at 152.4 102.87 0)
			(effects
				(font
					(size 1.524 1.524)
				)
				(justify left bottom)
				(hide yes)
			)
		)
		(property "Val" "0R"
			(at 149.86 105.41 0)
			(effects
				(font
					(size 1.27 1.27)
				)
			)
		)
		(property "Author" "Antmicro"
			(at 170.18 133.35 0)
			(effects
				(font
					(size 1.27 1.27)
					(thickness 0.15)
				)
				(justify left bottom)
				(hide yes)
			)
		)
		(property "License" "Apache-2.0"
			(at 170.18 135.89 0)
			(effects
				(font
					(size 1.27 1.27)
					(thickness 0.15)
				)
				(justify left bottom)
				(hide yes)
			)
		)
		(property "Max. Curr." "22.4A"
			(at 149.86 107.95 0)
			(effects
				(font
					(size 1.27 1.27)
					(thickness 0.15)
				)
			)
		)
		(property "Tolerance" "template_tolerance"
			(at 167.64 120.65 0)
			(effects
				(font
					(size 1.27 1.27)
				)
				(justify left bottom)
				(hide yes)
			)
		)
		(pin "1"
		)
		(pin "2"
		)
		(instances
			(project "cm4-baseboard"
				(path ""
					(reference "R308")
					(unit 1)
				)
			)
		)
	)
	(symbol
		(lib_id "antmicroTransistorsFETsMOSFETsSingle:SQS401EN-T1_BE3")
		(at 78.74 217.17 90)
		(unit 1)
		(exclude_from_sim no)
		(in_bom yes)
		(on_board yes)
		(dnp no)
		(fields_autoplaced yes)
		(property "Reference" "Q306"
			(at 76.2 204.47 90)
			(effects
				(font
					(size 1.27 1.27)
					(thickness 0.15)
				)
			)
		)
		(property "Value" "SQS401EN-T1_BE3"
			(at 88.9 201.93 0)
			(effects
				(font
					(size 1.27 1.27)
					(thickness 0.15)
				)
				(justify left bottom)
				(hide yes)
			)
		)
		(property "Footprint" "antmicro-footprints:Vishay_PowerPAK_1212-8_Single"
			(at 91.44 201.93 0)
			(effects
				(font
					(size 1.27 1.27)
					(thickness 0.15)
				)
				(justify left bottom)
				(hide yes)
			)
		)
		(property "Datasheet" "https://www.vishay.com/docs/65529/sqs401en.pdf"
			(at 93.98 201.93 0)
			(effects
				(font
					(size 1.27 1.27)
					(thickness 0.15)
				)
				(justify left bottom)
				(hide yes)
			)
		)
		(property "Description" ""
			(at 78.74 217.17 0)
			(effects
				(font
					(size 1.27 1.27)
				)
				(hide yes)
			)
		)
		(property "MPN" "SQS401EN-T1_BE3"
			(at 76.2 207.01 90)
			(effects
				(font
					(size 1.27 1.27)
					(thickness 0.15)
				)
			)
		)
		(property "Manufacturer" "Vishay"
			(at 96.52 201.93 0)
			(effects
				(font
					(size 1.27 1.27)
					(thickness 0.15)
				)
				(justify left bottom)
				(hide yes)
			)
		)
		(property "Author" "Antmicro"
			(at 99.06 201.93 0)
			(effects
				(font
					(size 1.27 1.27)
					(thickness 0.15)
				)
				(justify left bottom)
				(hide yes)
			)
		)
		(property "License" "Apache-2.0"
			(at 101.6 201.93 0)
			(effects
				(font
					(size 1.27 1.27)
					(thickness 0.15)
				)
				(justify left bottom)
				(hide yes)
			)
		)
		(pin "1"
		)
		(pin "2"
		)
		(pin "3"
		)
		(pin "4"
		)
		(pin "5"
		)
		(instances
			(project "cm4-baseboard"
				(path ""
					(reference "Q306")
					(unit 1)
				)
			)
		)
	)
	(symbol
		(lib_id "antmicroTestPoints:TP_0.75mm_SMD")
		(at 389.89 220.98 0)
		(unit 1)
		(exclude_from_sim no)
		(in_bom no)
		(on_board yes)
		(dnp no)
		(fields_autoplaced yes)
		(property "Reference" "TP309"
			(at 394.97 220.9799 0)
			(effects
				(font
					(size 1.27 1.27)
				)
				(justify left)
			)
		)
		(property "Value" "TP_0.75mm_SMD"
			(at 389.89 223.52 0)
			(effects
				(font
					(size 1.27 1.27)
				)
				(justify left bottom)
				(hide yes)
			)
		)
		(property "Footprint" "antmicro-footprints:TP_SMD_0.75mm"
			(at 394.97 215.9 0)
			(effects
				(font
					(size 1.524 1.524)
				)
				(justify left bottom)
				(hide yes)
			)
		)
		(property "Datasheet" ""
			(at 394.97 213.36 0)
			(effects
				(font
					(size 1.524 1.524)
				)
				(justify left bottom)
				(hide yes)
			)
		)
		(property "Description" ""
			(at 389.89 220.98 0)
			(effects
				(font
					(size 1.27 1.27)
				)
				(hide yes)
			)
		)
		(property "MPN" ""
			(at 389.89 220.98 0)
			(effects
				(font
					(size 1.27 1.27)
				)
				(hide yes)
			)
		)
		(property "Manufacturer" ""
			(at 389.89 220.98 0)
			(effects
				(font
					(size 1.27 1.27)
				)
				(hide yes)
			)
		)
		(property "Author" "Antmicro"
			(at 405.13 236.22 0)
			(effects
				(font
					(size 1.27 1.27)
					(thickness 0.15)
				)
				(justify left bottom)
				(hide yes)
			)
		)
		(property "License" "Apache-2.0"
			(at 405.13 238.76 0)
			(effects
				(font
					(size 1.27 1.27)
					(thickness 0.15)
				)
				(justify left bottom)
				(hide yes)
			)
		)
		(pin "1"
		)
		(instances
			(project "cm4-baseboard"
				(path ""
					(reference "TP309")
					(unit 1)
				)
			)
		)
	)
	(symbol
		(lib_id "antmicroTestPoints:TP_0.75mm_SMD")
		(at 285.75 180.34 90)
		(unit 1)
		(exclude_from_sim no)
		(in_bom no)
		(on_board yes)
		(dnp no)
		(property "Reference" "TP303"
			(at 278.13 177.8 90)
			(effects
				(font
					(size 1.27 1.27)
					(thickness 0.15)
				)
				(justify right)
			)
		)
		(property "Value" "TP_0.75mm_SMD"
			(at 293.37 165.1 0)
			(effects
				(font
					(size 1.27 1.27)
					(thickness 0.15)
				)
				(justify left bottom)
				(hide yes)
			)
		)
		(property "Footprint" "antmicro-footprints:TP_SMD_0.75mm"
			(at 292.1 169.545 0)
			(effects
				(font
					(size 1.27 1.27)
					(thickness 0.15)
				)
				(justify left bottom)
				(hide yes)
			)
		)
		(property "Datasheet" ""
			(at 298.45 162.56 0)
			(effects
				(font
					(size 1.27 1.27)
					(thickness 0.15)
				)
				(justify left bottom)
				(hide yes)
			)
		)
		(property "Description" ""
			(at 285.75 180.34 0)
			(effects
				(font
					(size 1.27 1.27)
				)
				(hide yes)
			)
		)
		(property "Author" "Antmicro"
			(at 294.64 169.545 0)
			(effects
				(font
					(size 1.27 1.27)
					(thickness 0.15)
				)
				(justify left bottom)
				(hide yes)
			)
		)
		(property "License" "Apache-2.0"
			(at 297.18 169.545 0)
			(effects
				(font
					(size 1.27 1.27)
					(thickness 0.15)
				)
				(justify left bottom)
				(hide yes)
			)
		)
		(property "MPN" ""
			(at 297.18 169.545 0)
			(effects
				(font
					(size 1.27 1.27)
					(thickness 0.15)
				)
				(justify left bottom)
				(hide yes)
			)
		)
		(property "Manufacturer" ""
			(at 292.1 169.545 0)
			(effects
				(font
					(size 1.27 1.27)
					(thickness 0.15)
				)
				(justify left bottom)
				(hide yes)
			)
		)
		(pin "1"
		)
		(instances
			(project "cm4-baseboard"
				(path ""
					(reference "TP303")
					(unit 1)
				)
			)
		)
	)
	(symbol
		(lib_id "antmicropower:GND")
		(at 334.01 238.76 0)
		(unit 1)
		(exclude_from_sim no)
		(in_bom yes)
		(on_board yes)
		(dnp no)
		(fields_autoplaced yes)
		(property "Reference" "#PWR0331"
			(at 342.9 241.3 0)
			(effects
				(font
					(size 1.27 1.27)
					(thickness 0.15)
				)
				(justify left bottom)
				(hide yes)
			)
		)
		(property "Value" "GND"
			(at 331.9998 243.84 0)
			(effects
				(font
					(size 1.27 1.27)
					(thickness 0.15)
				)
				(justify left bottom)
			)
		)
		(property "Footprint" ""
			(at 342.9 246.38 0)
			(effects
				(font
					(size 1.27 1.27)
					(thickness 0.15)
				)
				(justify left bottom)
				(hide yes)
			)
		)
		(property "Datasheet" ""
			(at 342.9 251.46 0)
			(effects
				(font
					(size 1.27 1.27)
					(thickness 0.15)
				)
				(justify left bottom)
				(hide yes)
			)
		)
		(property "Description" ""
			(at 334.01 238.76 0)
			(effects
				(font
					(size 1.27 1.27)
				)
				(hide yes)
			)
		)
		(property "Author" "Antmicro"
			(at 342.9 246.38 0)
			(effects
				(font
					(size 1.27 1.27)
					(thickness 0.15)
				)
				(justify left bottom)
				(hide yes)
			)
		)
		(property "License" "Apache-2.0"
			(at 342.9 248.92 0)
			(effects
				(font
					(size 1.27 1.27)
					(thickness 0.15)
				)
				(justify left bottom)
				(hide yes)
			)
		)
		(pin "1"
		)
		(instances
			(project "cm4-baseboard"
				(path ""
					(reference "#PWR0331")
					(unit 1)
				)
			)
		)
	)
	(symbol
		(lib_id "antmicroTestPoints:TP_0.75mm_SMD")
		(at 193.04 144.78 90)
		(unit 1)
		(exclude_from_sim no)
		(in_bom no)
		(on_board yes)
		(dnp no)
		(fields_autoplaced yes)
		(property "Reference" "TP302"
			(at 195.58 141.6049 90)
			(effects
				(font
					(size 1.27 1.27)
				)
				(justify right)
			)
		)
		(property "Value" "TP_0.75mm_SMD"
			(at 195.58 144.78 0)
			(effects
				(font
					(size 1.27 1.27)
				)
				(justify left bottom)
				(hide yes)
			)
		)
		(property "Footprint" "antmicro-footprints:TP_SMD_0.75mm"
			(at 187.96 139.7 0)
			(effects
				(font
					(size 1.524 1.524)
				)
				(justify left bottom)
				(hide yes)
			)
		)
		(property "Datasheet" ""
			(at 185.42 139.7 0)
			(effects
				(font
					(size 1.524 1.524)
				)
				(justify left bottom)
				(hide yes)
			)
		)
		(property "Description" ""
			(at 193.04 144.78 0)
			(effects
				(font
					(size 1.27 1.27)
				)
				(hide yes)
			)
		)
		(property "MPN" ""
			(at 193.04 144.78 0)
			(effects
				(font
					(size 1.27 1.27)
				)
				(hide yes)
			)
		)
		(property "Manufacturer" ""
			(at 193.04 144.78 0)
			(effects
				(font
					(size 1.27 1.27)
				)
				(hide yes)
			)
		)
		(property "Author" "Antmicro"
			(at 208.28 129.54 0)
			(effects
				(font
					(size 1.27 1.27)
					(thickness 0.15)
				)
				(justify left bottom)
				(hide yes)
			)
		)
		(property "License" "Apache-2.0"
			(at 210.82 129.54 0)
			(effects
				(font
					(size 1.27 1.27)
					(thickness 0.15)
				)
				(justify left bottom)
				(hide yes)
			)
		)
		(pin "1"
		)
		(instances
			(project "cm4-baseboard"
				(path ""
					(reference "TP302")
					(unit 1)
				)
			)
		)
	)
	(symbol
		(lib_id "antmicropower:GND")
		(at 264.16 119.38 0)
		(unit 1)
		(exclude_from_sim no)
		(in_bom yes)
		(on_board yes)
		(dnp no)
		(property "Reference" "#PWR0318"
			(at 264.16 125.73 0)
			(effects
				(font
					(size 1.27 1.27)
				)
				(justify left bottom)
				(hide yes)
			)
		)
		(property "Value" "GND"
			(at 264.16 123.19 0)
			(effects
				(font
					(size 1.27 1.27)
				)
			)
		)
		(property "Footprint" ""
			(at 273.05 127 0)
			(effects
				(font
					(size 1.27 1.27)
					(thickness 0.15)
				)
				(justify left bottom)
				(hide yes)
			)
		)
		(property "Datasheet" ""
			(at 273.05 132.08 0)
			(effects
				(font
					(size 1.27 1.27)
					(thickness 0.15)
				)
				(justify left bottom)
				(hide yes)
			)
		)
		(property "Description" ""
			(at 264.16 119.38 0)
			(effects
				(font
					(size 1.27 1.27)
				)
				(hide yes)
			)
		)
		(property "Author" "Antmicro"
			(at 273.05 127 0)
			(effects
				(font
					(size 1.27 1.27)
					(thickness 0.15)
				)
				(justify left bottom)
				(hide yes)
			)
		)
		(property "License" "Apache-2.0"
			(at 273.05 129.54 0)
			(effects
				(font
					(size 1.27 1.27)
					(thickness 0.15)
				)
				(justify left bottom)
				(hide yes)
			)
		)
		(pin "1"
		)
		(instances
			(project "cm4-baseboard"
				(path ""
					(reference "#PWR0318")
					(unit 1)
				)
			)
		)
	)
	(symbol
		(lib_id "antmicroResistors0402:R_33k_0402")
		(at 66.04 193.04 90)
		(unit 1)
		(exclude_from_sim no)
		(in_bom yes)
		(on_board yes)
		(dnp no)
		(property "Reference" "R302"
			(at 67.31 189.23 90)
			(effects
				(font
					(size 1.27 1.27)
					(thickness 0.15)
				)
				(justify right)
			)
		)
		(property "Value" "R_33k_0402"
			(at 78.74 172.72 0)
			(effects
				(font
					(size 1.27 1.27)
					(thickness 0.15)
				)
				(justify left bottom)
				(hide yes)
			)
		)
		(property "Footprint" "antmicro-footprints:R_0402_1005Metric"
			(at 81.28 172.72 0)
			(effects
				(font
					(size 1.27 1.27)
					(thickness 0.15)
				)
				(justify left bottom)
				(hide yes)
			)
		)
		(property "Datasheet" "https://www.bourns.com/docs/product-datasheets/cr.pdf"
			(at 83.82 172.72 0)
			(effects
				(font
					(size 1.27 1.27)
					(thickness 0.15)
				)
				(justify left bottom)
				(hide yes)
			)
		)
		(property "Description" ""
			(at 66.04 193.04 0)
			(effects
				(font
					(size 1.27 1.27)
				)
				(hide yes)
			)
		)
		(property "MPN" "CR0402-FX-3302GLF"
			(at 86.36 172.72 0)
			(effects
				(font
					(size 1.27 1.27)
					(thickness 0.15)
				)
				(justify left bottom)
				(hide yes)
			)
		)
		(property "Manufacturer" "Bourns"
			(at 88.9 172.72 0)
			(effects
				(font
					(size 1.27 1.27)
					(thickness 0.15)
				)
				(justify left bottom)
				(hide yes)
			)
		)
		(property "License" "Apache-2.0"
			(at 91.44 172.72 0)
			(effects
				(font
					(size 1.27 1.27)
					(thickness 0.15)
				)
				(justify left bottom)
				(hide yes)
			)
		)
		(property "Author" "Antmicro"
			(at 93.98 172.72 0)
			(effects
				(font
					(size 1.27 1.27)
					(thickness 0.15)
				)
				(justify left bottom)
				(hide yes)
			)
		)
		(property "Val" "33k"
			(at 67.31 191.77 90)
			(effects
				(font
					(size 1.27 1.27)
					(thickness 0.15)
				)
				(justify right)
			)
		)
		(property "Tolerance" "1%"
			(at 76.2 172.72 0)
			(effects
				(font
					(size 1.27 1.27)
				)
				(justify left bottom)
				(hide yes)
			)
		)
		(pin "2"
		)
		(pin "1"
		)
		(instances
			(project "cm4-baseboard"
				(path ""
					(reference "R302")
					(unit 1)
				)
			)
		)
	)
	(symbol
		(lib_id "antmicropower:+3V3")
		(at 381 218.44 0)
		(unit 1)
		(exclude_from_sim no)
		(in_bom yes)
		(on_board yes)
		(dnp no)
		(fields_autoplaced yes)
		(property "Reference" "#PWR0340"
			(at 381 222.25 0)
			(effects
				(font
					(size 1.27 1.27)
				)
				(justify left bottom)
				(hide yes)
			)
		)
		(property "Value" "+3V3"
			(at 381 213.36 0)
			(effects
				(font
					(size 1.27 1.27)
				)
			)
		)
		(property "Footprint" ""
			(at 381 218.44 0)
			(effects
				(font
					(size 1.27 1.27)
				)
				(justify left bottom)
				(hide yes)
			)
		)
		(property "Datasheet" ""
			(at 381 218.44 0)
			(effects
				(font
					(size 1.27 1.27)
				)
				(justify left bottom)
				(hide yes)
			)
		)
		(property "Description" ""
			(at 381 218.44 0)
			(effects
				(font
					(size 1.27 1.27)
				)
				(hide yes)
			)
		)
		(property "Author" "Antmicro"
			(at 396.24 220.98 0)
			(effects
				(font
					(size 1.27 1.27)
					(thickness 0.15)
				)
				(justify left bottom)
				(hide yes)
			)
		)
		(property "License" "Apache-2.0"
			(at 396.24 223.52 0)
			(effects
				(font
					(size 1.27 1.27)
					(thickness 0.15)
				)
				(justify left bottom)
				(hide yes)
			)
		)
		(pin "1"
		)
		(instances
			(project "cm4-baseboard"
				(path ""
					(reference "#PWR0340")
					(unit 1)
				)
			)
		)
	)
	(symbol
		(lib_id "antmicropower:GND")
		(at 271.78 194.31 0)
		(unit 1)
		(exclude_from_sim no)
		(in_bom yes)
		(on_board yes)
		(dnp no)
		(fields_autoplaced yes)
		(property "Reference" "#PWR0319"
			(at 280.67 196.85 0)
			(effects
				(font
					(size 1.27 1.27)
					(thickness 0.15)
				)
				(justify left bottom)
				(hide yes)
			)
		)
		(property "Value" "GND"
			(at 269.7698 199.39 0)
			(effects
				(font
					(size 1.27 1.27)
					(thickness 0.15)
				)
				(justify left bottom)
			)
		)
		(property "Footprint" ""
			(at 280.67 201.93 0)
			(effects
				(font
					(size 1.27 1.27)
					(thickness 0.15)
				)
				(justify left bottom)
				(hide yes)
			)
		)
		(property "Datasheet" ""
			(at 280.67 207.01 0)
			(effects
				(font
					(size 1.27 1.27)
					(thickness 0.15)
				)
				(justify left bottom)
				(hide yes)
			)
		)
		(property "Description" ""
			(at 271.78 194.31 0)
			(effects
				(font
					(size 1.27 1.27)
				)
				(hide yes)
			)
		)
		(property "Author" "Antmicro"
			(at 280.67 201.93 0)
			(effects
				(font
					(size 1.27 1.27)
					(thickness 0.15)
				)
				(justify left bottom)
				(hide yes)
			)
		)
		(property "License" "Apache-2.0"
			(at 280.67 204.47 0)
			(effects
				(font
					(size 1.27 1.27)
					(thickness 0.15)
				)
				(justify left bottom)
				(hide yes)
			)
		)
		(pin "1"
		)
		(instances
			(project "cm4-baseboard"
				(path ""
					(reference "#PWR0319")
					(unit 1)
				)
			)
		)
	)
	(symbol
		(lib_id "antmicropower:GND")
		(at 279.4 234.95 0)
		(unit 1)
		(exclude_from_sim no)
		(in_bom yes)
		(on_board yes)
		(dnp no)
		(fields_autoplaced yes)
		(property "Reference" "#PWR0322"
			(at 288.29 237.49 0)
			(effects
				(font
					(size 1.27 1.27)
					(thickness 0.15)
				)
				(justify left bottom)
				(hide yes)
			)
		)
		(property "Value" "GND"
			(at 277.3898 240.03 0)
			(effects
				(font
					(size 1.27 1.27)
					(thickness 0.15)
				)
				(justify left bottom)
			)
		)
		(property "Footprint" ""
			(at 288.29 242.57 0)
			(effects
				(font
					(size 1.27 1.27)
					(thickness 0.15)
				)
				(justify left bottom)
				(hide yes)
			)
		)
		(property "Datasheet" ""
			(at 288.29 247.65 0)
			(effects
				(font
					(size 1.27 1.27)
					(thickness 0.15)
				)
				(justify left bottom)
				(hide yes)
			)
		)
		(property "Description" ""
			(at 279.4 234.95 0)
			(effects
				(font
					(size 1.27 1.27)
				)
				(hide yes)
			)
		)
		(property "Author" "Antmicro"
			(at 288.29 242.57 0)
			(effects
				(font
					(size 1.27 1.27)
					(thickness 0.15)
				)
				(justify left bottom)
				(hide yes)
			)
		)
		(property "License" "Apache-2.0"
			(at 288.29 245.11 0)
			(effects
				(font
					(size 1.27 1.27)
					(thickness 0.15)
				)
				(justify left bottom)
				(hide yes)
			)
		)
		(pin "1"
		)
		(instances
			(project "cm4-baseboard"
				(path ""
					(reference "#PWR0322")
					(unit 1)
				)
			)
		)
	)
	(symbol
		(lib_id "antmicropower:GND")
		(at 388.62 193.04 0)
		(mirror y)
		(unit 1)
		(exclude_from_sim no)
		(in_bom yes)
		(on_board yes)
		(dnp no)
		(fields_autoplaced yes)
		(property "Reference" "#PWR0343"
			(at 379.73 195.58 0)
			(effects
				(font
					(size 1.27 1.27)
					(thickness 0.15)
				)
				(justify left bottom)
				(hide yes)
			)
		)
		(property "Value" "GND"
			(at 390.6302 198.12 0)
			(effects
				(font
					(size 1.27 1.27)
					(thickness 0.15)
				)
				(justify left bottom)
			)
		)
		(property "Footprint" ""
			(at 379.73 200.66 0)
			(effects
				(font
					(size 1.27 1.27)
					(thickness 0.15)
				)
				(justify left bottom)
				(hide yes)
			)
		)
		(property "Datasheet" ""
			(at 379.73 205.74 0)
			(effects
				(font
					(size 1.27 1.27)
					(thickness 0.15)
				)
				(justify left bottom)
				(hide yes)
			)
		)
		(property "Description" ""
			(at 388.62 193.04 0)
			(effects
				(font
					(size 1.27 1.27)
				)
				(hide yes)
			)
		)
		(property "Author" "Antmicro"
			(at 379.73 200.66 0)
			(effects
				(font
					(size 1.27 1.27)
					(thickness 0.15)
				)
				(justify left bottom)
				(hide yes)
			)
		)
		(property "License" "Apache-2.0"
			(at 379.73 203.2 0)
			(effects
				(font
					(size 1.27 1.27)
					(thickness 0.15)
				)
				(justify left bottom)
				(hide yes)
			)
		)
		(pin "1"
		)
		(instances
			(project "cm4-baseboard"
				(path ""
					(reference "#PWR0343")
					(unit 1)
				)
			)
		)
	)
	(symbol
		(lib_id "antmicroCapacitors0402:C_100n_0402")
		(at 273.05 113.03 270)
		(unit 1)
		(exclude_from_sim no)
		(in_bom yes)
		(on_board yes)
		(dnp no)
		(property "Reference" "C307"
			(at 274.32 114.3 90)
			(effects
				(font
					(size 1.27 1.27)
				)
				(justify left)
			)
		)
		(property "Value" "C_100n_0402"
			(at 269.24 113.03 0)
			(effects
				(font
					(size 1.27 1.27)
				)
				(justify left bottom)
				(hide yes)
			)
		)
		(property "Footprint" "antmicro-footprints:C_0402_1005Metric"
			(at 278.13 118.11 0)
			(effects
				(font
					(size 1.524 1.524)
				)
				(justify left bottom)
				(hide yes)
			)
		)
		(property "Datasheet" "https://www.murata.com/products/productdetail?partno=GRM155R61H104KE14%23"
			(at 273.05 113.03 0)
			(effects
				(font
					(size 1.27 1.27)
				)
				(justify left bottom)
				(hide yes)
			)
		)
		(property "Description" ""
			(at 273.05 113.03 0)
			(effects
				(font
					(size 1.27 1.27)
				)
				(hide yes)
			)
		)
		(property "Manufacturer" "Murata"
			(at 283.21 118.11 0)
			(effects
				(font
					(size 1.524 1.524)
				)
				(justify left bottom)
				(hide yes)
			)
		)
		(property "MPN" "GRM155R61H104KE14D"
			(at 280.67 118.11 0)
			(effects
				(font
					(size 1.524 1.524)
				)
				(justify left bottom)
				(hide yes)
			)
		)
		(property "Val" "100n"
			(at 274.32 116.84 90)
			(effects
				(font
					(size 1.27 1.27)
				)
				(justify left)
			)
		)
		(property "License" "Apache-2.0"
			(at 250.19 133.35 0)
			(effects
				(font
					(size 1.27 1.27)
					(thickness 0.15)
				)
				(justify left bottom)
				(hide yes)
			)
		)
		(property "Author" "Antmicro"
			(at 247.65 133.35 0)
			(effects
				(font
					(size 1.27 1.27)
					(thickness 0.15)
				)
				(justify left bottom)
				(hide yes)
			)
		)
		(property "Voltage" "50V"
			(at 245.11 133.35 0)
			(effects
				(font
					(size 1.27 1.27)
				)
				(justify left bottom)
				(hide yes)
			)
		)
		(property "Dielectric" "X5R"
			(at 242.57 133.35 0)
			(effects
				(font
					(size 1.27 1.27)
				)
				(justify left bottom)
				(hide yes)
			)
		)
		(pin "1"
		)
		(pin "2"
		)
		(instances
			(project "cm4-baseboard"
				(path ""
					(reference "C307")
					(unit 1)
				)
			)
		)
	)
	(symbol
		(lib_id "antmicroCapacitorsmisc:C_22u_25V_0805")
		(at 354.33 113.03 90)
		(mirror x)
		(unit 1)
		(exclude_from_sim no)
		(in_bom yes)
		(on_board yes)
		(dnp no)
		(fields_autoplaced yes)
		(property "Reference" "C315"
			(at 351.79 113.0362 90)
			(effects
				(font
					(size 1.27 1.27)
				)
				(justify left)
			)
		)
		(property "Value" "C_22u_25V_0805"
			(at 358.14 113.03 0)
			(effects
				(font
					(size 1.27 1.27)
				)
				(justify left bottom)
				(hide yes)
			)
		)
		(property "Footprint" "antmicro-footprints:C_0805_2012Metric"
			(at 349.25 118.11 0)
			(effects
				(font
					(size 1.524 1.524)
				)
				(justify left bottom)
				(hide yes)
			)
		)
		(property "Datasheet" "https://product.samsungsem.com/mlcc/CL21A226MAYNNN.do"
			(at 354.33 113.03 0)
			(effects
				(font
					(size 1.27 1.27)
				)
				(justify left bottom)
				(hide yes)
			)
		)
		(property "Description" ""
			(at 354.33 113.03 0)
			(effects
				(font
					(size 1.27 1.27)
				)
				(hide yes)
			)
		)
		(property "Manufacturer" "Samsung Electro-Mechanics"
			(at 344.17 118.11 0)
			(effects
				(font
					(size 1.524 1.524)
				)
				(justify left bottom)
				(hide yes)
			)
		)
		(property "MPN" "CL21A226MAYNNNE"
			(at 346.71 118.11 0)
			(effects
				(font
					(size 1.524 1.524)
				)
				(justify left bottom)
				(hide yes)
			)
		)
		(property "Val" "22u"
			(at 351.79 115.5762 90)
			(effects
				(font
					(size 1.27 1.27)
				)
				(justify left)
			)
		)
		(property "License" "Apache-2.0"
			(at 377.19 133.35 0)
			(effects
				(font
					(size 1.27 1.27)
					(thickness 0.15)
				)
				(justify left bottom)
				(hide yes)
			)
		)
		(property "Author" "Antmicro"
			(at 379.73 133.35 0)
			(effects
				(font
					(size 1.27 1.27)
					(thickness 0.15)
				)
				(justify left bottom)
				(hide yes)
			)
		)
		(property "Voltage" "25V"
			(at 351.79 118.1162 90)
			(effects
				(font
					(size 1.27 1.27)
				)
				(justify left)
			)
		)
		(property "Dielectric" "X5R"
			(at 384.81 133.35 0)
			(effects
				(font
					(size 1.27 1.27)
				)
				(justify left bottom)
				(hide yes)
			)
		)
		(property "Public" "False"
			(at 387.35 133.35 0)
			(effects
				(font
					(size 1.27 1.27)
				)
				(justify left bottom)
				(hide yes)
			)
		)
		(pin "1"
		)
		(pin "2"
		)
		(instances
			(project "cm4-baseboard"
				(path ""
					(reference "C315")
					(unit 1)
				)
			)
		)
	)
	(symbol
		(lib_id "antmicropower:PWR_FLAG")
		(at 97.79 120.65 0)
		(unit 1)
		(exclude_from_sim no)
		(in_bom yes)
		(on_board yes)
		(dnp no)
		(property "Reference" "#FLG05"
			(at 97.79 118.745 0)
			(effects
				(font
					(size 1.27 1.27)
				)
				(hide yes)
			)
		)
		(property "Value" "PWR_FLAG"
			(at 97.79 116.84 0)
			(effects
				(font
					(size 1.27 1.27)
				)
			)
		)
		(property "Footprint" ""
			(at 97.79 120.65 0)
			(effects
				(font
					(size 1.27 1.27)
				)
				(hide yes)
			)
		)
		(property "Datasheet" ""
			(at 97.79 120.65 0)
			(effects
				(font
					(size 1.27 1.27)
				)
				(hide yes)
			)
		)
		(property "Description" ""
			(at 97.79 120.65 0)
			(effects
				(font
					(size 1.27 1.27)
				)
				(hide yes)
			)
		)
		(pin "1"
		)
		(instances
			(project "cm4-baseboard"
				(path ""
					(reference "#FLG05")
					(unit 1)
				)
			)
		)
	)
	(symbol
		(lib_id "antmicropower:VCC")
		(at 185.42 119.38 0)
		(unit 1)
		(exclude_from_sim no)
		(in_bom yes)
		(on_board yes)
		(dnp no)
		(fields_autoplaced yes)
		(property "Reference" "#PWR0311"
			(at 185.42 123.19 0)
			(effects
				(font
					(size 1.27 1.27)
				)
				(justify left bottom)
				(hide yes)
			)
		)
		(property "Value" "VCC"
			(at 185.42 114.3 0)
			(effects
				(font
					(size 1.27 1.27)
				)
			)
		)
		(property "Footprint" ""
			(at 185.42 119.38 0)
			(effects
				(font
					(size 1.27 1.27)
				)
				(justify left bottom)
				(hide yes)
			)
		)
		(property "Datasheet" ""
			(at 185.42 119.38 0)
			(effects
				(font
					(size 1.27 1.27)
				)
				(justify left bottom)
				(hide yes)
			)
		)
		(property "Description" ""
			(at 185.42 119.38 0)
			(effects
				(font
					(size 1.27 1.27)
				)
				(hide yes)
			)
		)
		(pin "1"
		)
		(instances
			(project "cm4-baseboard"
				(path ""
					(reference "#PWR0311")
					(unit 1)
				)
			)
		)
	)
	(symbol
		(lib_id "antmicropower:GND")
		(at 363.22 119.38 0)
		(unit 1)
		(exclude_from_sim no)
		(in_bom yes)
		(on_board yes)
		(dnp no)
		(property "Reference" "#PWR0338"
			(at 363.22 125.73 0)
			(effects
				(font
					(size 1.27 1.27)
				)
				(justify left bottom)
				(hide yes)
			)
		)
		(property "Value" "GND"
			(at 363.22 123.19 0)
			(effects
				(font
					(size 1.27 1.27)
				)
			)
		)
		(property "Footprint" ""
			(at 372.11 127 0)
			(effects
				(font
					(size 1.27 1.27)
					(thickness 0.15)
				)
				(justify left bottom)
				(hide yes)
			)
		)
		(property "Datasheet" ""
			(at 372.11 132.08 0)
			(effects
				(font
					(size 1.27 1.27)
					(thickness 0.15)
				)
				(justify left bottom)
				(hide yes)
			)
		)
		(property "Description" ""
			(at 363.22 119.38 0)
			(effects
				(font
					(size 1.27 1.27)
				)
				(hide yes)
			)
		)
		(property "Author" "Antmicro"
			(at 372.11 127 0)
			(effects
				(font
					(size 1.27 1.27)
					(thickness 0.15)
				)
				(justify left bottom)
				(hide yes)
			)
		)
		(property "License" "Apache-2.0"
			(at 372.11 129.54 0)
			(effects
				(font
					(size 1.27 1.27)
					(thickness 0.15)
				)
				(justify left bottom)
				(hide yes)
			)
		)
		(pin "1"
		)
		(instances
			(project "cm4-baseboard"
				(path ""
					(reference "#PWR0338")
					(unit 1)
				)
			)
		)
	)
	(symbol
		(lib_id "antmicroLEDIndicationDiscrete:LED_G_0603_KP-1608CGCK")
		(at 388.62 233.68 270)
		(mirror x)
		(unit 1)
		(exclude_from_sim no)
		(in_bom yes)
		(on_board yes)
		(dnp no)
		(property "Reference" "D306"
			(at 394.97 229.87 90)
			(effects
				(font
					(size 1.27 1.27)
					(thickness 0.15)
				)
			)
		)
		(property "Value" "LED_G_0603_KP-1608CGCK"
			(at 381 210.82 0)
			(effects
				(font
					(size 1.27 1.27)
					(thickness 0.15)
				)
				(justify left bottom)
				(hide yes)
			)
		)
		(property "Footprint" "antmicro-footprints:LED_0603_1608Metric_G"
			(at 378.46 210.82 0)
			(effects
				(font
					(size 1.27 1.27)
					(thickness 0.15)
				)
				(justify left bottom)
				(hide yes)
			)
		)
		(property "Datasheet" "http://www.kingbright.com/attachments/file/psearch//000/00/00/KP-1608CGCK(Ver.23B).pdf"
			(at 375.92 210.82 0)
			(effects
				(font
					(size 1.27 1.27)
					(thickness 0.15)
				)
				(justify left bottom)
				(hide yes)
			)
		)
		(property "Description" ""
			(at 388.62 233.68 0)
			(effects
				(font
					(size 1.27 1.27)
				)
				(hide yes)
			)
		)
		(property "MPN" "KP-1608CGCK"
			(at 373.38 210.82 0)
			(effects
				(font
					(size 1.27 1.27)
					(thickness 0.15)
				)
				(justify left bottom)
				(hide yes)
			)
		)
		(property "Manufacturer" "Kingbright"
			(at 370.84 210.82 0)
			(effects
				(font
					(size 1.27 1.27)
					(thickness 0.15)
				)
				(justify left bottom)
				(hide yes)
			)
		)
		(property "Color" "Green"
			(at 394.97 232.41 90)
			(effects
				(font
					(size 1.27 1.27)
				)
			)
		)
		(property "Author" "Antmicro"
			(at 368.3 210.82 0)
			(effects
				(font
					(size 1.27 1.27)
					(thickness 0.15)
				)
				(justify left bottom)
				(hide yes)
			)
		)
		(property "License" "Apache-2.0"
			(at 365.76 210.82 0)
			(effects
				(font
					(size 1.27 1.27)
					(thickness 0.15)
				)
				(justify left bottom)
				(hide yes)
			)
		)
		(pin "2"
		)
		(pin "1"
		)
		(instances
			(project "cm4-baseboard"
				(path ""
					(reference "D306")
					(unit 1)
				)
			)
		)
	)
	(symbol
		(lib_id "antmicroDCDCConverters:AP62301_TSOT")
		(at 290.83 175.26 0)
		(unit 1)
		(exclude_from_sim no)
		(in_bom yes)
		(on_board yes)
		(dnp no)
		(fields_autoplaced yes)
		(property "Reference" "U301"
			(at 300.99 167.64 0)
			(effects
				(font
					(size 1.27 1.27)
					(thickness 0.15)
				)
			)
		)
		(property "Value" "AP62301_TSOT"
			(at 326.39 182.88 0)
			(effects
				(font
					(size 1.27 1.27)
					(thickness 0.15)
				)
				(justify left bottom)
				(hide yes)
			)
		)
		(property "Footprint" "antmicro-footprints:TSOT23-6"
			(at 326.39 185.42 0)
			(effects
				(font
					(size 1.27 1.27)
					(thickness 0.15)
				)
				(justify left bottom)
				(hide yes)
			)
		)
		(property "Datasheet" "https://www.diodes.com/assets/Datasheets/AP62300_AP62301_AP62300T.pdf"
			(at 326.39 187.96 0)
			(effects
				(font
					(size 1.27 1.27)
					(thickness 0.15)
				)
				(justify left bottom)
				(hide yes)
			)
		)
		(property "Description" ""
			(at 290.83 175.26 0)
			(effects
				(font
					(size 1.27 1.27)
				)
				(hide yes)
			)
		)
		(property "MPN" "AP62301WU-7"
			(at 300.99 170.18 0)
			(effects
				(font
					(size 1.27 1.27)
					(thickness 0.15)
				)
			)
		)
		(property "Manufacturer" "Diodes Incorporated"
			(at 326.39 190.5 0)
			(effects
				(font
					(size 1.27 1.27)
					(thickness 0.15)
				)
				(justify left bottom)
				(hide yes)
			)
		)
		(property "Author" "Antmicro"
			(at 326.39 193.04 0)
			(effects
				(font
					(size 1.27 1.27)
					(thickness 0.15)
				)
				(justify left bottom)
				(hide yes)
			)
		)
		(property "License" "Apache-2.0"
			(at 326.39 195.58 0)
			(effects
				(font
					(size 1.27 1.27)
					(thickness 0.15)
				)
				(justify left bottom)
				(hide yes)
			)
		)
		(pin "1"
		)
		(pin "2"
		)
		(pin "3"
		)
		(pin "4"
		)
		(pin "5"
		)
		(pin "6"
		)
		(instances
			(project "cm4-baseboard"
				(path ""
					(reference "U301")
					(unit 1)
				)
			)
		)
	)
	(symbol
		(lib_id "antmicroCapacitors0402:C_100n_0402")
		(at 318.77 180.34 180)
		(unit 1)
		(exclude_from_sim no)
		(in_bom yes)
		(on_board yes)
		(dnp no)
		(property "Reference" "C308"
			(at 316.23 177.8 0)
			(effects
				(font
					(size 1.27 1.27)
					(thickness 0.15)
				)
			)
		)
		(property "Value" "C_100n_0402"
			(at 298.45 170.18 0)
			(effects
				(font
					(size 1.27 1.27)
					(thickness 0.15)
				)
				(justify left bottom)
				(hide yes)
			)
		)
		(property "Footprint" "antmicro-footprints:C_0402_1005Metric"
			(at 298.45 167.64 0)
			(effects
				(font
					(size 1.27 1.27)
					(thickness 0.15)
				)
				(justify left bottom)
				(hide yes)
			)
		)
		(property "Datasheet" "https://www.murata.com/products/productdetail?partno=GRM155R61H104KE14%23"
			(at 298.45 165.1 0)
			(effects
				(font
					(size 1.27 1.27)
					(thickness 0.15)
				)
				(justify left bottom)
				(hide yes)
			)
		)
		(property "Description" ""
			(at 318.77 180.34 0)
			(effects
				(font
					(size 1.27 1.27)
				)
				(hide yes)
			)
		)
		(property "Manufacturer" "Murata"
			(at 298.45 160.02 0)
			(effects
				(font
					(size 1.27 1.27)
					(thickness 0.15)
				)
				(justify left bottom)
				(hide yes)
			)
		)
		(property "MPN" "GRM155R61H104KE14D"
			(at 298.45 162.56 0)
			(effects
				(font
					(size 1.27 1.27)
					(thickness 0.15)
				)
				(justify left bottom)
				(hide yes)
			)
		)
		(property "Val" "100n"
			(at 316.23 182.88 0)
			(effects
				(font
					(size 1.27 1.27)
					(thickness 0.15)
				)
			)
		)
		(property "License" "Apache-2.0"
			(at 298.45 157.48 0)
			(effects
				(font
					(size 1.27 1.27)
					(thickness 0.15)
				)
				(justify left bottom)
				(hide yes)
			)
		)
		(property "Author" "Antmicro"
			(at 298.45 154.94 0)
			(effects
				(font
					(size 1.27 1.27)
					(thickness 0.15)
				)
				(justify left bottom)
				(hide yes)
			)
		)
		(property "Voltage" "50V"
			(at 298.45 152.4 0)
			(effects
				(font
					(size 1.27 1.27)
				)
				(justify left bottom)
				(hide yes)
			)
		)
		(property "Dielectric" "X5R"
			(at 298.45 149.86 0)
			(effects
				(font
					(size 1.27 1.27)
				)
				(justify left bottom)
				(hide yes)
			)
		)
		(pin "1"
		)
		(pin "2"
		)
		(instances
			(project "cm4-baseboard"
				(path ""
					(reference "C308")
					(unit 1)
				)
			)
		)
	)
	(symbol
		(lib_id "antmicropower:GND")
		(at 66.04 194.31 0)
		(unit 1)
		(exclude_from_sim no)
		(in_bom yes)
		(on_board yes)
		(dnp no)
		(property "Reference" "#PWR0304"
			(at 66.04 200.66 0)
			(effects
				(font
					(size 1.27 1.27)
				)
				(justify left bottom)
				(hide yes)
			)
		)
		(property "Value" "GND"
			(at 67.945 198.12 0)
			(effects
				(font
					(size 1.27 1.27)
				)
				(justify right)
			)
		)
		(property "Footprint" ""
			(at 74.93 201.93 0)
			(effects
				(font
					(size 1.27 1.27)
					(thickness 0.15)
				)
				(justify left bottom)
				(hide yes)
			)
		)
		(property "Datasheet" ""
			(at 74.93 207.01 0)
			(effects
				(font
					(size 1.27 1.27)
					(thickness 0.15)
				)
				(justify left bottom)
				(hide yes)
			)
		)
		(property "Description" ""
			(at 66.04 194.31 0)
			(effects
				(font
					(size 1.27 1.27)
				)
				(hide yes)
			)
		)
		(property "Author" "Antmicro"
			(at 74.93 201.93 0)
			(effects
				(font
					(size 1.27 1.27)
					(thickness 0.15)
				)
				(justify left bottom)
				(hide yes)
			)
		)
		(property "License" "Apache-2.0"
			(at 74.93 204.47 0)
			(effects
				(font
					(size 1.27 1.27)
					(thickness 0.15)
				)
				(justify left bottom)
				(hide yes)
			)
		)
		(pin "1"
		)
		(instances
			(project "cm4-baseboard"
				(path ""
					(reference "#PWR0304")
					(unit 1)
				)
			)
		)
	)
	(symbol
		(lib_id "antmicroResistors0603:R_0R_22.4A_0603")
		(at 361.95 220.98 0)
		(unit 1)
		(exclude_from_sim no)
		(in_bom yes)
		(on_board yes)
		(dnp no)
		(property "Reference" "R323"
			(at 364.49 215.9 0)
			(effects
				(font
					(size 1.27 1.27)
				)
			)
		)
		(property "Value" "R_0R_22.4A_0603"
			(at 361.95 224.79 0)
			(effects
				(font
					(size 1.27 1.27)
				)
				(justify left bottom)
				(hide yes)
			)
		)
		(property "Footprint" "antmicro-footprints:R_0603_1608Metric"
			(at 367.03 215.9 0)
			(effects
				(font
					(size 1.524 1.524)
				)
				(justify left bottom)
				(hide yes)
			)
		)
		(property "Datasheet" "https://fscdn.rohm.com/en/products/databook/datasheet/passive/resistor/chip_resistor/pmr-jpw-e.pdf"
			(at 361.95 220.98 0)
			(effects
				(font
					(size 1.27 1.27)
				)
				(justify left bottom)
				(hide yes)
			)
		)
		(property "Description" ""
			(at 361.95 220.98 0)
			(effects
				(font
					(size 1.27 1.27)
				)
				(hide yes)
			)
		)
		(property "Manufacturer" "ROHM Semiconductor"
			(at 367.03 210.82 0)
			(effects
				(font
					(size 1.524 1.524)
				)
				(justify left bottom)
				(hide yes)
			)
		)
		(property "MPN" "PMR03EZPJ000"
			(at 367.03 213.36 0)
			(effects
				(font
					(size 1.524 1.524)
				)
				(justify left bottom)
				(hide yes)
			)
		)
		(property "Val" "0R"
			(at 364.49 218.44 0)
			(effects
				(font
					(size 1.27 1.27)
				)
			)
		)
		(property "Author" "Antmicro"
			(at 384.81 243.84 0)
			(effects
				(font
					(size 1.27 1.27)
					(thickness 0.15)
				)
				(justify left bottom)
				(hide yes)
			)
		)
		(property "License" "Apache-2.0"
			(at 384.81 246.38 0)
			(effects
				(font
					(size 1.27 1.27)
					(thickness 0.15)
				)
				(justify left bottom)
				(hide yes)
			)
		)
		(property "Max. Curr." "22.4A"
			(at 361.95 224.155 0)
			(effects
				(font
					(size 1.27 1.27)
					(thickness 0.15)
				)
				(justify left bottom)
			)
		)
		(property "Tolerance" "template_tolerance"
			(at 382.27 231.14 0)
			(effects
				(font
					(size 1.27 1.27)
				)
				(justify left bottom)
				(hide yes)
			)
		)
		(pin "1"
		)
		(pin "2"
		)
		(instances
			(project "cm4-baseboard"
				(path ""
					(reference "R323")
					(unit 1)
				)
			)
		)
	)
	(symbol
		(lib_id "antmicropower:+5V")
		(at 381 107.95 0)
		(unit 1)
		(exclude_from_sim no)
		(in_bom yes)
		(on_board yes)
		(dnp no)
		(property "Reference" "#PWR0339"
			(at 381 111.76 0)
			(effects
				(font
					(size 1.27 1.27)
				)
				(justify left bottom)
				(hide yes)
			)
		)
		(property "Value" "+5V"
			(at 381 104.14 0)
			(effects
				(font
					(size 1.27 1.27)
				)
			)
		)
		(property "Footprint" ""
			(at 396.24 115.57 0)
			(effects
				(font
					(size 1.27 1.27)
					(thickness 0.15)
				)
				(justify left bottom)
				(hide yes)
			)
		)
		(property "Datasheet" ""
			(at 396.24 118.11 0)
			(effects
				(font
					(size 1.27 1.27)
					(thickness 0.15)
				)
				(justify left bottom)
				(hide yes)
			)
		)
		(property "Description" ""
			(at 381 107.95 0)
			(effects
				(font
					(size 1.27 1.27)
				)
				(hide yes)
			)
		)
		(property "Author" "Antmicro"
			(at 396.24 115.57 0)
			(effects
				(font
					(size 1.27 1.27)
					(thickness 0.15)
				)
				(justify left bottom)
				(hide yes)
			)
		)
		(property "License" "Apache-2.0"
			(at 396.24 118.11 0)
			(effects
				(font
					(size 1.27 1.27)
					(thickness 0.15)
				)
				(justify left bottom)
				(hide yes)
			)
		)
		(pin "1"
		)
		(instances
			(project "cm4-baseboard"
				(path ""
					(reference "#PWR0339")
					(unit 1)
				)
			)
		)
	)
	(symbol
		(lib_id "antmicroCapacitorsmisc:C_22u_25V_0805")
		(at 355.6 181.61 90)
		(mirror x)
		(unit 1)
		(exclude_from_sim no)
		(in_bom yes)
		(on_board yes)
		(dnp no)
		(fields_autoplaced yes)
		(property "Reference" "C316"
			(at 358.14 181.6163 90)
			(effects
				(font
					(size 1.27 1.27)
				)
				(justify right)
			)
		)
		(property "Value" "C_22u_25V_0805"
			(at 359.41 181.61 0)
			(effects
				(font
					(size 1.27 1.27)
				)
				(justify left bottom)
				(hide yes)
			)
		)
		(property "Footprint" "antmicro-footprints:C_0805_2012Metric"
			(at 350.52 186.69 0)
			(effects
				(font
					(size 1.524 1.524)
				)
				(justify left bottom)
				(hide yes)
			)
		)
		(property "Datasheet" "https://product.samsungsem.com/mlcc/CL21A226MAYNNN.do"
			(at 355.6 181.61 0)
			(effects
				(font
					(size 1.27 1.27)
				)
				(justify left bottom)
				(hide yes)
			)
		)
		(property "Description" ""
			(at 355.6 181.61 0)
			(effects
				(font
					(size 1.27 1.27)
				)
				(hide yes)
			)
		)
		(property "Manufacturer" "Samsung Electro-Mechanics"
			(at 345.44 186.69 0)
			(effects
				(font
					(size 1.524 1.524)
				)
				(justify left bottom)
				(hide yes)
			)
		)
		(property "MPN" "CL21A226MAYNNNE"
			(at 347.98 186.69 0)
			(effects
				(font
					(size 1.524 1.524)
				)
				(justify left bottom)
				(hide yes)
			)
		)
		(property "Val" "22u"
			(at 358.14 184.1563 90)
			(effects
				(font
					(size 1.27 1.27)
				)
				(justify right)
			)
		)
		(property "License" "Apache-2.0"
			(at 378.46 201.93 0)
			(effects
				(font
					(size 1.27 1.27)
					(thickness 0.15)
				)
				(justify left bottom)
				(hide yes)
			)
		)
		(property "Author" "Antmicro"
			(at 381 201.93 0)
			(effects
				(font
					(size 1.27 1.27)
					(thickness 0.15)
				)
				(justify left bottom)
				(hide yes)
			)
		)
		(property "Voltage" "25V"
			(at 358.14 186.6963 90)
			(effects
				(font
					(size 1.27 1.27)
				)
				(justify right)
			)
		)
		(property "Dielectric" "X5R"
			(at 386.08 201.93 0)
			(effects
				(font
					(size 1.27 1.27)
				)
				(justify left bottom)
				(hide yes)
			)
		)
		(property "Public" "False"
			(at 388.62 201.93 0)
			(effects
				(font
					(size 1.27 1.27)
				)
				(justify left bottom)
				(hide yes)
			)
		)
		(pin "1"
		)
		(pin "2"
		)
		(instances
			(project "cm4-baseboard"
				(path ""
					(reference "C316")
					(unit 1)
				)
			)
		)
	)
	(symbol
		(lib_id "antmicropower:GND")
		(at 388.62 236.22 0)
		(mirror y)
		(unit 1)
		(exclude_from_sim no)
		(in_bom yes)
		(on_board yes)
		(dnp no)
		(fields_autoplaced yes)
		(property "Reference" "#PWR0345"
			(at 379.73 238.76 0)
			(effects
				(font
					(size 1.27 1.27)
					(thickness 0.15)
				)
				(justify left bottom)
				(hide yes)
			)
		)
		(property "Value" "GND"
			(at 390.6302 241.3 0)
			(effects
				(font
					(size 1.27 1.27)
					(thickness 0.15)
				)
				(justify left bottom)
			)
		)
		(property "Footprint" ""
			(at 379.73 243.84 0)
			(effects
				(font
					(size 1.27 1.27)
					(thickness 0.15)
				)
				(justify left bottom)
				(hide yes)
			)
		)
		(property "Datasheet" ""
			(at 379.73 248.92 0)
			(effects
				(font
					(size 1.27 1.27)
					(thickness 0.15)
				)
				(justify left bottom)
				(hide yes)
			)
		)
		(property "Description" ""
			(at 388.62 236.22 0)
			(effects
				(font
					(size 1.27 1.27)
				)
				(hide yes)
			)
		)
		(property "Author" "Antmicro"
			(at 379.73 243.84 0)
			(effects
				(font
					(size 1.27 1.27)
					(thickness 0.15)
				)
				(justify left bottom)
				(hide yes)
			)
		)
		(property "License" "Apache-2.0"
			(at 379.73 246.38 0)
			(effects
				(font
					(size 1.27 1.27)
					(thickness 0.15)
				)
				(justify left bottom)
				(hide yes)
			)
		)
		(pin "1"
		)
		(instances
			(project "cm4-baseboard"
				(path ""
					(reference "#PWR0345")
					(unit 1)
				)
			)
		)
	)
	(symbol
		(lib_id "antmicroTestPoints:TP_0.75mm_SMD")
		(at 389.89 115.57 0)
		(unit 1)
		(exclude_from_sim no)
		(in_bom no)
		(on_board yes)
		(dnp no)
		(fields_autoplaced yes)
		(property "Reference" "TP305"
			(at 394.97 115.5699 0)
			(effects
				(font
					(size 1.27 1.27)
				)
				(justify left)
			)
		)
		(property "Value" "TP_0.75mm_SMD"
			(at 389.89 118.11 0)
			(effects
				(font
					(size 1.27 1.27)
				)
				(justify left bottom)
				(hide yes)
			)
		)
		(property "Footprint" "antmicro-footprints:TP_SMD_0.75mm"
			(at 394.97 110.49 0)
			(effects
				(font
					(size 1.524 1.524)
				)
				(justify left bottom)
				(hide yes)
			)
		)
		(property "Datasheet" ""
			(at 394.97 107.95 0)
			(effects
				(font
					(size 1.524 1.524)
				)
				(justify left bottom)
				(hide yes)
			)
		)
		(property "Description" ""
			(at 389.89 115.57 0)
			(effects
				(font
					(size 1.27 1.27)
				)
				(hide yes)
			)
		)
		(property "MPN" ""
			(at 389.89 115.57 0)
			(effects
				(font
					(size 1.27 1.27)
				)
				(hide yes)
			)
		)
		(property "Manufacturer" ""
			(at 389.89 115.57 0)
			(effects
				(font
					(size 1.27 1.27)
				)
				(hide yes)
			)
		)
		(property "Author" "Antmicro"
			(at 405.13 130.81 0)
			(effects
				(font
					(size 1.27 1.27)
					(thickness 0.15)
				)
				(justify left bottom)
				(hide yes)
			)
		)
		(property "License" "Apache-2.0"
			(at 405.13 133.35 0)
			(effects
				(font
					(size 1.27 1.27)
					(thickness 0.15)
				)
				(justify left bottom)
				(hide yes)
			)
		)
		(pin "1"
		)
		(instances
			(project "cm4-baseboard"
				(path ""
					(reference "TP305")
					(unit 1)
				)
			)
		)
	)
	(symbol
		(lib_id "antmicroCapacitorsmisc:C_22u_25V_0805")
		(at 270.51 227.33 90)
		(mirror x)
		(unit 1)
		(exclude_from_sim no)
		(in_bom yes)
		(on_board yes)
		(dnp no)
		(fields_autoplaced yes)
		(property "Reference" "C306"
			(at 267.97 227.3362 90)
			(effects
				(font
					(size 1.27 1.27)
				)
				(justify left)
			)
		)
		(property "Value" "C_22u_25V_0805"
			(at 274.32 227.33 0)
			(effects
				(font
					(size 1.27 1.27)
				)
				(justify left bottom)
				(hide yes)
			)
		)
		(property "Footprint" "antmicro-footprints:C_0805_2012Metric"
			(at 265.43 232.41 0)
			(effects
				(font
					(size 1.524 1.524)
				)
				(justify left bottom)
				(hide yes)
			)
		)
		(property "Datasheet" "https://product.samsungsem.com/mlcc/CL21A226MAYNNN.do"
			(at 270.51 227.33 0)
			(effects
				(font
					(size 1.27 1.27)
				)
				(justify left bottom)
				(hide yes)
			)
		)
		(property "Description" ""
			(at 270.51 227.33 0)
			(effects
				(font
					(size 1.27 1.27)
				)
				(hide yes)
			)
		)
		(property "Manufacturer" "Samsung Electro-Mechanics"
			(at 260.35 232.41 0)
			(effects
				(font
					(size 1.524 1.524)
				)
				(justify left bottom)
				(hide yes)
			)
		)
		(property "MPN" "CL21A226MAYNNNE"
			(at 262.89 232.41 0)
			(effects
				(font
					(size 1.524 1.524)
				)
				(justify left bottom)
				(hide yes)
			)
		)
		(property "Val" "22u"
			(at 267.97 229.8762 90)
			(effects
				(font
					(size 1.27 1.27)
				)
				(justify left)
			)
		)
		(property "License" "Apache-2.0"
			(at 293.37 247.65 0)
			(effects
				(font
					(size 1.27 1.27)
					(thickness 0.15)
				)
				(justify left bottom)
				(hide yes)
			)
		)
		(property "Author" "Antmicro"
			(at 295.91 247.65 0)
			(effects
				(font
					(size 1.27 1.27)
					(thickness 0.15)
				)
				(justify left bottom)
				(hide yes)
			)
		)
		(property "Voltage" "25V"
			(at 267.97 232.4162 90)
			(effects
				(font
					(size 1.27 1.27)
				)
				(justify left)
			)
		)
		(property "Dielectric" "X5R"
			(at 300.99 247.65 0)
			(effects
				(font
					(size 1.27 1.27)
				)
				(justify left bottom)
				(hide yes)
			)
		)
		(property "Public" "False"
			(at 303.53 247.65 0)
			(effects
				(font
					(size 1.27 1.27)
				)
				(justify left bottom)
				(hide yes)
			)
		)
		(pin "1"
		)
		(pin "2"
		)
		(instances
			(project "cm4-baseboard"
				(path ""
					(reference "C306")
					(unit 1)
				)
			)
		)
	)
	(symbol
		(lib_id "antmicroResistors0603:R_0R_22.4A_0603")
		(at 361.95 175.26 0)
		(unit 1)
		(exclude_from_sim no)
		(in_bom yes)
		(on_board yes)
		(dnp no)
		(property "Reference" "R322"
			(at 364.49 170.18 0)
			(effects
				(font
					(size 1.27 1.27)
				)
			)
		)
		(property "Value" "R_0R_22.4A_0603"
			(at 361.95 179.07 0)
			(effects
				(font
					(size 1.27 1.27)
				)
				(justify left bottom)
				(hide yes)
			)
		)
		(property "Footprint" "antmicro-footprints:R_0603_1608Metric"
			(at 367.03 170.18 0)
			(effects
				(font
					(size 1.524 1.524)
				)
				(justify left bottom)
				(hide yes)
			)
		)
		(property "Datasheet" "https://fscdn.rohm.com/en/products/databook/datasheet/passive/resistor/chip_resistor/pmr-jpw-e.pdf"
			(at 361.95 175.26 0)
			(effects
				(font
					(size 1.27 1.27)
				)
				(justify left bottom)
				(hide yes)
			)
		)
		(property "Description" ""
			(at 361.95 175.26 0)
			(effects
				(font
					(size 1.27 1.27)
				)
				(hide yes)
			)
		)
		(property "Manufacturer" "ROHM Semiconductor"
			(at 367.03 165.1 0)
			(effects
				(font
					(size 1.524 1.524)
				)
				(justify left bottom)
				(hide yes)
			)
		)
		(property "MPN" "PMR03EZPJ000"
			(at 367.03 167.64 0)
			(effects
				(font
					(size 1.524 1.524)
				)
				(justify left bottom)
				(hide yes)
			)
		)
		(property "Val" "0R"
			(at 364.49 172.72 0)
			(effects
				(font
					(size 1.27 1.27)
				)
			)
		)
		(property "Author" "Antmicro"
			(at 384.81 198.12 0)
			(effects
				(font
					(size 1.27 1.27)
					(thickness 0.15)
				)
				(justify left bottom)
				(hide yes)
			)
		)
		(property "License" "Apache-2.0"
			(at 384.81 200.66 0)
			(effects
				(font
					(size 1.27 1.27)
					(thickness 0.15)
				)
				(justify left bottom)
				(hide yes)
			)
		)
		(property "Max. Curr." "22.4A"
			(at 361.95 178.435 0)
			(effects
				(font
					(size 1.27 1.27)
					(thickness 0.15)
				)
				(justify left bottom)
			)
		)
		(property "Tolerance" "template_tolerance"
			(at 382.27 185.42 0)
			(effects
				(font
					(size 1.27 1.27)
				)
				(justify left bottom)
				(hide yes)
			)
		)
		(pin "1"
		)
		(pin "2"
		)
		(instances
			(project "cm4-baseboard"
				(path ""
					(reference "R322")
					(unit 1)
				)
			)
		)
	)
	(symbol
		(lib_id "antmicroLEDIndicationDiscrete:LED_G_0603_KP-1608CGCK")
		(at 388.62 190.5 270)
		(mirror x)
		(unit 1)
		(exclude_from_sim no)
		(in_bom yes)
		(on_board yes)
		(dnp no)
		(property "Reference" "D305"
			(at 394.97 186.69 90)
			(effects
				(font
					(size 1.27 1.27)
					(thickness 0.15)
				)
			)
		)
		(property "Value" "LED_G_0603_KP-1608CGCK"
			(at 381 167.64 0)
			(effects
				(font
					(size 1.27 1.27)
					(thickness 0.15)
				)
				(justify left bottom)
				(hide yes)
			)
		)
		(property "Footprint" "antmicro-footprints:LED_0603_1608Metric_G"
			(at 378.46 167.64 0)
			(effects
				(font
					(size 1.27 1.27)
					(thickness 0.15)
				)
				(justify left bottom)
				(hide yes)
			)
		)
		(property "Datasheet" "http://www.kingbright.com/attachments/file/psearch//000/00/00/KP-1608CGCK(Ver.23B).pdf"
			(at 375.92 167.64 0)
			(effects
				(font
					(size 1.27 1.27)
					(thickness 0.15)
				)
				(justify left bottom)
				(hide yes)
			)
		)
		(property "Description" ""
			(at 388.62 190.5 0)
			(effects
				(font
					(size 1.27 1.27)
				)
				(hide yes)
			)
		)
		(property "MPN" "KP-1608CGCK"
			(at 373.38 167.64 0)
			(effects
				(font
					(size 1.27 1.27)
					(thickness 0.15)
				)
				(justify left bottom)
				(hide yes)
			)
		)
		(property "Manufacturer" "Kingbright"
			(at 370.84 167.64 0)
			(effects
				(font
					(size 1.27 1.27)
					(thickness 0.15)
				)
				(justify left bottom)
				(hide yes)
			)
		)
		(property "Color" "Green"
			(at 394.97 189.23 90)
			(effects
				(font
					(size 1.27 1.27)
				)
			)
		)
		(property "Author" "Antmicro"
			(at 368.3 167.64 0)
			(effects
				(font
					(size 1.27 1.27)
					(thickness 0.15)
				)
				(justify left bottom)
				(hide yes)
			)
		)
		(property "License" "Apache-2.0"
			(at 365.76 167.64 0)
			(effects
				(font
					(size 1.27 1.27)
					(thickness 0.15)
				)
				(justify left bottom)
				(hide yes)
			)
		)
		(pin "2"
		)
		(pin "1"
		)
		(instances
			(project "cm4-baseboard"
				(path ""
					(reference "D305")
					(unit 1)
				)
			)
		)
	)
	(symbol
		(lib_id "antmicropower:GND")
		(at 355.6 238.76 0)
		(unit 1)
		(exclude_from_sim no)
		(in_bom yes)
		(on_board yes)
		(dnp no)
		(fields_autoplaced yes)
		(property "Reference" "#PWR0337"
			(at 364.49 241.3 0)
			(effects
				(font
					(size 1.27 1.27)
					(thickness 0.15)
				)
				(justify left bottom)
				(hide yes)
			)
		)
		(property "Value" "GND"
			(at 353.5898 243.84 0)
			(effects
				(font
					(size 1.27 1.27)
					(thickness 0.15)
				)
				(justify left bottom)
			)
		)
		(property "Footprint" ""
			(at 364.49 246.38 0)
			(effects
				(font
					(size 1.27 1.27)
					(thickness 0.15)
				)
				(justify left bottom)
				(hide yes)
			)
		)
		(property "Datasheet" ""
			(at 364.49 251.46 0)
			(effects
				(font
					(size 1.27 1.27)
					(thickness 0.15)
				)
				(justify left bottom)
				(hide yes)
			)
		)
		(property "Description" ""
			(at 355.6 238.76 0)
			(effects
				(font
					(size 1.27 1.27)
				)
				(hide yes)
			)
		)
		(property "Author" "Antmicro"
			(at 364.49 246.38 0)
			(effects
				(font
					(size 1.27 1.27)
					(thickness 0.15)
				)
				(justify left bottom)
				(hide yes)
			)
		)
		(property "License" "Apache-2.0"
			(at 364.49 248.92 0)
			(effects
				(font
					(size 1.27 1.27)
					(thickness 0.15)
				)
				(justify left bottom)
				(hide yes)
			)
		)
		(pin "1"
		)
		(instances
			(project "cm4-baseboard"
				(path ""
					(reference "#PWR0337")
					(unit 1)
				)
			)
		)
	)
	(symbol
		(lib_id "antmicroTransistorsFETsMOSFETsSingle:SQS401EN-T1_BE3")
		(at 78.74 128.27 90)
		(unit 1)
		(exclude_from_sim no)
		(in_bom yes)
		(on_board yes)
		(dnp no)
		(fields_autoplaced yes)
		(property "Reference" "Q304"
			(at 76.2 115.57 90)
			(effects
				(font
					(size 1.27 1.27)
					(thickness 0.15)
				)
			)
		)
		(property "Value" "SQS401EN-T1_BE3"
			(at 88.9 113.03 0)
			(effects
				(font
					(size 1.27 1.27)
					(thickness 0.15)
				)
				(justify left bottom)
				(hide yes)
			)
		)
		(property "Footprint" "antmicro-footprints:Vishay_PowerPAK_1212-8_Single"
			(at 91.44 113.03 0)
			(effects
				(font
					(size 1.27 1.27)
					(thickness 0.15)
				)
				(justify left bottom)
				(hide yes)
			)
		)
		(property "Datasheet" "https://www.vishay.com/docs/65529/sqs401en.pdf"
			(at 93.98 113.03 0)
			(effects
				(font
					(size 1.27 1.27)
					(thickness 0.15)
				)
				(justify left bottom)
				(hide yes)
			)
		)
		(property "Description" ""
			(at 78.74 128.27 0)
			(effects
				(font
					(size 1.27 1.27)
				)
				(hide yes)
			)
		)
		(property "MPN" "SQS401EN-T1_BE3"
			(at 76.2 118.11 90)
			(effects
				(font
					(size 1.27 1.27)
					(thickness 0.15)
				)
			)
		)
		(property "Manufacturer" "Vishay"
			(at 96.52 113.03 0)
			(effects
				(font
					(size 1.27 1.27)
					(thickness 0.15)
				)
				(justify left bottom)
				(hide yes)
			)
		)
		(property "Author" "Antmicro"
			(at 99.06 113.03 0)
			(effects
				(font
					(size 1.27 1.27)
					(thickness 0.15)
				)
				(justify left bottom)
				(hide yes)
			)
		)
		(property "License" "Apache-2.0"
			(at 101.6 113.03 0)
			(effects
				(font
					(size 1.27 1.27)
					(thickness 0.15)
				)
				(justify left bottom)
				(hide yes)
			)
		)
		(pin "1"
		)
		(pin "2"
		)
		(pin "3"
		)
		(pin "5"
		)
		(pin "4"
		)
		(instances
			(project "cm4-baseboard"
				(path ""
					(reference "Q304")
					(unit 1)
				)
			)
		)
	)
	(symbol
		(lib_id "antmicroCapacitorsmisc:C_22u_25V_0805")
		(at 264.16 113.03 90)
		(mirror x)
		(unit 1)
		(exclude_from_sim no)
		(in_bom yes)
		(on_board yes)
		(dnp no)
		(fields_autoplaced yes)
		(property "Reference" "C304"
			(at 266.7 113.0362 90)
			(effects
				(font
					(size 1.27 1.27)
				)
				(justify right)
			)
		)
		(property "Value" "C_22u_25V_0805"
			(at 267.97 113.03 0)
			(effects
				(font
					(size 1.27 1.27)
				)
				(justify left bottom)
				(hide yes)
			)
		)
		(property "Footprint" "antmicro-footprints:C_0805_2012Metric"
			(at 259.08 118.11 0)
			(effects
				(font
					(size 1.524 1.524)
				)
				(justify left bottom)
				(hide yes)
			)
		)
		(property "Datasheet" "https://product.samsungsem.com/mlcc/CL21A226MAYNNN.do"
			(at 264.16 113.03 0)
			(effects
				(font
					(size 1.27 1.27)
				)
				(justify left bottom)
				(hide yes)
			)
		)
		(property "Description" ""
			(at 264.16 113.03 0)
			(effects
				(font
					(size 1.27 1.27)
				)
				(hide yes)
			)
		)
		(property "Manufacturer" "Samsung Electro-Mechanics"
			(at 254 118.11 0)
			(effects
				(font
					(size 1.524 1.524)
				)
				(justify left bottom)
				(hide yes)
			)
		)
		(property "MPN" "CL21A226MAYNNNE"
			(at 256.54 118.11 0)
			(effects
				(font
					(size 1.524 1.524)
				)
				(justify left bottom)
				(hide yes)
			)
		)
		(property "Val" "22u"
			(at 266.7 115.5762 90)
			(effects
				(font
					(size 1.27 1.27)
				)
				(justify right)
			)
		)
		(property "License" "Apache-2.0"
			(at 287.02 133.35 0)
			(effects
				(font
					(size 1.27 1.27)
					(thickness 0.15)
				)
				(justify left bottom)
				(hide yes)
			)
		)
		(property "Author" "Antmicro"
			(at 289.56 133.35 0)
			(effects
				(font
					(size 1.27 1.27)
					(thickness 0.15)
				)
				(justify left bottom)
				(hide yes)
			)
		)
		(property "Voltage" "25V"
			(at 266.7 118.1162 90)
			(effects
				(font
					(size 1.27 1.27)
				)
				(justify right)
			)
		)
		(property "Dielectric" "X5R"
			(at 294.64 133.35 0)
			(effects
				(font
					(size 1.27 1.27)
				)
				(justify left bottom)
				(hide yes)
			)
		)
		(property "Public" "False"
			(at 297.18 133.35 0)
			(effects
				(font
					(size 1.27 1.27)
				)
				(justify left bottom)
				(hide yes)
			)
		)
		(pin "1"
		)
		(pin "2"
		)
		(instances
			(project "cm4-baseboard"
				(path ""
					(reference "C304")
					(unit 1)
				)
			)
		)
	)
	(symbol
		(lib_id "antmicroCapacitorsmisc:C_22u_25V_0805")
		(at 271.78 181.61 90)
		(mirror x)
		(unit 1)
		(exclude_from_sim no)
		(in_bom yes)
		(on_board yes)
		(dnp no)
		(fields_autoplaced yes)
		(property "Reference" "C305"
			(at 269.24 181.6162 90)
			(effects
				(font
					(size 1.27 1.27)
				)
				(justify left)
			)
		)
		(property "Value" "C_22u_25V_0805"
			(at 275.59 181.61 0)
			(effects
				(font
					(size 1.27 1.27)
				)
				(justify left bottom)
				(hide yes)
			)
		)
		(property "Footprint" "antmicro-footprints:C_0805_2012Metric"
			(at 266.7 186.69 0)
			(effects
				(font
					(size 1.524 1.524)
				)
				(justify left bottom)
				(hide yes)
			)
		)
		(property "Datasheet" "https://product.samsungsem.com/mlcc/CL21A226MAYNNN.do"
			(at 271.78 181.61 0)
			(effects
				(font
					(size 1.27 1.27)
				)
				(justify left bottom)
				(hide yes)
			)
		)
		(property "Description" ""
			(at 271.78 181.61 0)
			(effects
				(font
					(size 1.27 1.27)
				)
				(hide yes)
			)
		)
		(property "Manufacturer" "Samsung Electro-Mechanics"
			(at 261.62 186.69 0)
			(effects
				(font
					(size 1.524 1.524)
				)
				(justify left bottom)
				(hide yes)
			)
		)
		(property "MPN" "CL21A226MAYNNNE"
			(at 264.16 186.69 0)
			(effects
				(font
					(size 1.524 1.524)
				)
				(justify left bottom)
				(hide yes)
			)
		)
		(property "Val" "22u"
			(at 269.24 184.1562 90)
			(effects
				(font
					(size 1.27 1.27)
				)
				(justify left)
			)
		)
		(property "License" "Apache-2.0"
			(at 294.64 201.93 0)
			(effects
				(font
					(size 1.27 1.27)
					(thickness 0.15)
				)
				(justify left bottom)
				(hide yes)
			)
		)
		(property "Author" "Antmicro"
			(at 297.18 201.93 0)
			(effects
				(font
					(size 1.27 1.27)
					(thickness 0.15)
				)
				(justify left bottom)
				(hide yes)
			)
		)
		(property "Voltage" "25V"
			(at 269.24 186.6962 90)
			(effects
				(font
					(size 1.27 1.27)
				)
				(justify left)
			)
		)
		(property "Dielectric" "X5R"
			(at 302.26 201.93 0)
			(effects
				(font
					(size 1.27 1.27)
				)
				(justify left bottom)
				(hide yes)
			)
		)
		(property "Public" "False"
			(at 304.8 201.93 0)
			(effects
				(font
					(size 1.27 1.27)
				)
				(justify left bottom)
				(hide yes)
			)
		)
		(pin "1"
		)
		(pin "2"
		)
		(instances
			(project "cm4-baseboard"
				(path ""
					(reference "C305")
					(unit 1)
				)
			)
		)
	)
	(symbol
		(lib_id "antmicroDCDCConverters:AP62600SJ-7")
		(at 294.64 110.49 0)
		(unit 1)
		(exclude_from_sim no)
		(in_bom yes)
		(on_board yes)
		(dnp no)
		(fields_autoplaced yes)
		(property "Reference" "U303"
			(at 306.07 102.87 0)
			(effects
				(font
					(size 1.27 1.27)
					(thickness 0.15)
				)
			)
		)
		(property "Value" "AP62600SJ-7"
			(at 330.2 118.11 0)
			(effects
				(font
					(size 1.27 1.27)
					(thickness 0.15)
				)
				(justify left bottom)
				(hide yes)
			)
		)
		(property "Footprint" "antmicro-footprints:V-QFN2030-12"
			(at 330.2 120.65 0)
			(effects
				(font
					(size 1.27 1.27)
					(thickness 0.15)
				)
				(justify left bottom)
				(hide yes)
			)
		)
		(property "Datasheet" "https://www.diodes.com/assets/Datasheets/AP62600.pdf"
			(at 330.2 123.19 0)
			(effects
				(font
					(size 1.27 1.27)
					(thickness 0.15)
				)
				(justify left bottom)
				(hide yes)
			)
		)
		(property "Description" ""
			(at 294.64 110.49 0)
			(effects
				(font
					(size 1.27 1.27)
				)
				(hide yes)
			)
		)
		(property "MPN" "AP62600SJ-7"
			(at 306.07 105.41 0)
			(effects
				(font
					(size 1.27 1.27)
					(thickness 0.15)
				)
			)
		)
		(property "Manufacturer" "Diodes Incorporated"
			(at 330.2 125.73 0)
			(effects
				(font
					(size 1.27 1.27)
					(thickness 0.15)
				)
				(justify left bottom)
				(hide yes)
			)
		)
		(property "Author" "Antmicro"
			(at 330.2 128.27 0)
			(effects
				(font
					(size 1.27 1.27)
					(thickness 0.15)
				)
				(justify left bottom)
				(hide yes)
			)
		)
		(property "License" "Apache-2.0"
			(at 330.2 130.81 0)
			(effects
				(font
					(size 1.27 1.27)
					(thickness 0.15)
				)
				(justify left bottom)
				(hide yes)
			)
		)
		(pin "1"
		)
		(pin "10"
		)
		(pin "11"
		)
		(pin "12"
		)
		(pin "2"
		)
		(pin "3"
		)
		(pin "4"
		)
		(pin "5"
		)
		(pin "6"
		)
		(pin "7"
		)
		(pin "8"
		)
		(pin "9"
		)
		(instances
			(project "cm4-baseboard"
				(path ""
					(reference "U303")
					(unit 1)
				)
			)
		)
	)
	(symbol
		(lib_id "antmicroResistors0402:R_10k_0402")
		(at 281.94 129.54 90)
		(unit 1)
		(exclude_from_sim no)
		(in_bom yes)
		(on_board yes)
		(dnp no)
		(property "Reference" "R314"
			(at 283.21 125.73 90)
			(effects
				(font
					(size 1.27 1.27)
					(thickness 0.15)
				)
				(justify right)
			)
		)
		(property "Value" "R_10k_0402"
			(at 294.64 109.22 0)
			(effects
				(font
					(size 1.27 1.27)
					(thickness 0.15)
				)
				(justify left bottom)
				(hide yes)
			)
		)
		(property "Footprint" "antmicro-footprints:R_0402_1005Metric"
			(at 297.18 109.22 0)
			(effects
				(font
					(size 1.27 1.27)
					(thickness 0.15)
				)
				(justify left bottom)
				(hide yes)
			)
		)
		(property "Datasheet" "https://www.bourns.com/docs/product-datasheets/cr.pdf"
			(at 299.72 109.22 0)
			(effects
				(font
					(size 1.27 1.27)
					(thickness 0.15)
				)
				(justify left bottom)
				(hide yes)
			)
		)
		(property "Description" ""
			(at 281.94 129.54 0)
			(effects
				(font
					(size 1.27 1.27)
				)
				(hide yes)
			)
		)
		(property "Manufacturer" "Bourns"
			(at 304.8 109.22 0)
			(effects
				(font
					(size 1.27 1.27)
					(thickness 0.15)
				)
				(justify left bottom)
				(hide yes)
			)
		)
		(property "MPN" "CR0402-FX-1002GLF"
			(at 302.26 109.22 0)
			(effects
				(font
					(size 1.27 1.27)
					(thickness 0.15)
				)
				(justify left bottom)
				(hide yes)
			)
		)
		(property "Val" "10k"
			(at 283.21 128.27 90)
			(effects
				(font
					(size 1.27 1.27)
					(thickness 0.15)
				)
				(justify right)
			)
		)
		(property "License" "Apache-2.0"
			(at 307.34 109.22 0)
			(effects
				(font
					(size 1.27 1.27)
					(thickness 0.15)
				)
				(justify left bottom)
				(hide yes)
			)
		)
		(property "Author" "Antmicro"
			(at 309.88 109.22 0)
			(effects
				(font
					(size 1.27 1.27)
					(thickness 0.15)
				)
				(justify left bottom)
				(hide yes)
			)
		)
		(property "Tolerance" "1%"
			(at 292.1 109.22 0)
			(effects
				(font
					(size 1.27 1.27)
				)
				(justify left bottom)
				(hide yes)
			)
		)
		(pin "1"
		)
		(pin "2"
		)
		(instances
			(project "cm4-baseboard"
				(path ""
					(reference "R314")
					(unit 1)
				)
			)
		)
	)
	(symbol
		(lib_id "antmicropower:PWR_FLAG")
		(at 373.38 107.95 0)
		(unit 1)
		(exclude_from_sim no)
		(in_bom yes)
		(on_board yes)
		(dnp no)
		(property "Reference" "#FLG06"
			(at 373.38 106.045 0)
			(effects
				(font
					(size 1.27 1.27)
				)
				(hide yes)
			)
		)
		(property "Value" "PWR_FLAG"
			(at 373.38 104.14 0)
			(effects
				(font
					(size 1.27 1.27)
				)
			)
		)
		(property "Footprint" ""
			(at 373.38 107.95 0)
			(effects
				(font
					(size 1.27 1.27)
				)
				(hide yes)
			)
		)
		(property "Datasheet" ""
			(at 373.38 107.95 0)
			(effects
				(font
					(size 1.27 1.27)
				)
				(hide yes)
			)
		)
		(property "Description" ""
			(at 373.38 107.95 0)
			(effects
				(font
					(size 1.27 1.27)
				)
				(hide yes)
			)
		)
		(pin "1"
		)
		(instances
			(project "cm4-baseboard"
				(path ""
					(reference "#FLG06")
					(unit 1)
				)
			)
		)
	)
	(symbol
		(lib_id "antmicroFixedInductors:L_1u_5.5A_Bourns-SRP3212A")
		(at 323.85 220.98 0)
		(unit 1)
		(exclude_from_sim no)
		(in_bom yes)
		(on_board yes)
		(dnp no)
		(fields_autoplaced yes)
		(property "Reference" "L302"
			(at 326.39 215.9 0)
			(effects
				(font
					(size 1.27 1.27)
					(thickness 0.15)
				)
			)
		)
		(property "Value" "L_1u_5.5A_Bourns-SRP3212A"
			(at 326.39 215.9 0)
			(effects
				(font
					(size 1.27 1.27)
					(thickness 0.15)
				)
				(hide yes)
			)
		)
		(property "Footprint" "antmicro-footprints:L_Bourns-SRP3212A"
			(at 337.82 228.6 0)
			(effects
				(font
					(size 1.27 1.27)
					(thickness 0.15)
				)
				(justify left bottom)
				(hide yes)
			)
		)
		(property "Datasheet" "https://www.mouser.com/datasheet/2/54/SRP3212A-3011944.pdf"
			(at 337.82 231.14 0)
			(effects
				(font
					(size 1.27 1.27)
					(thickness 0.15)
				)
				(justify left bottom)
				(hide yes)
			)
		)
		(property "Description" ""
			(at 323.85 220.98 0)
			(effects
				(font
					(size 1.27 1.27)
				)
				(hide yes)
			)
		)
		(property "Manufacturer" "Bourns"
			(at 337.82 233.68 0)
			(effects
				(font
					(size 1.27 1.27)
					(thickness 0.15)
				)
				(justify left bottom)
				(hide yes)
			)
		)
		(property "MPN" "SRP3212A-1R0M"
			(at 337.82 236.22 0)
			(effects
				(font
					(size 1.27 1.27)
					(thickness 0.15)
				)
				(justify left bottom)
				(hide yes)
			)
		)
		(property "Size" "3.2x2.5"
			(at 337.82 243.84 0)
			(effects
				(font
					(size 1.27 1.27)
					(thickness 0.15)
				)
				(justify left bottom)
				(hide yes)
			)
		)
		(property "Val" "1u/5.5A"
			(at 326.39 218.44 0)
			(effects
				(font
					(size 1.27 1.27)
					(thickness 0.15)
				)
			)
		)
		(property "Author" "Antmicro"
			(at 337.82 246.38 0)
			(effects
				(font
					(size 1.27 1.27)
					(thickness 0.15)
				)
				(justify left bottom)
				(hide yes)
			)
		)
		(property "License" "Apache-2.0"
			(at 337.82 248.92 0)
			(effects
				(font
					(size 1.27 1.27)
					(thickness 0.15)
				)
				(justify left bottom)
				(hide yes)
			)
		)
		(property "ISat" "6.5 A"
			(at 337.82 237.49 0)
			(effects
				(font
					(size 1.27 1.27)
				)
				(justify left)
				(hide yes)
			)
		)
		(property "IMax" "5.5 A"
			(at 337.82 241.3 0)
			(effects
				(font
					(size 1.27 1.27)
					(thickness 0.15)
				)
				(justify left bottom)
				(hide yes)
			)
		)
		(pin "1"
		)
		(pin "2"
		)
		(instances
			(project "cm4-baseboard"
				(path ""
					(reference "L302")
					(unit 1)
				)
			)
		)
	)
	(symbol
		(lib_id "antmicroTransistorsFETsMOSFETsSingle:SQS401EN-T1_BE3")
		(at 147.32 128.27 270)
		(mirror x)
		(unit 1)
		(exclude_from_sim no)
		(in_bom yes)
		(on_board yes)
		(dnp no)
		(property "Reference" "Q307"
			(at 149.86 115.57 90)
			(effects
				(font
					(size 1.27 1.27)
					(thickness 0.15)
				)
			)
		)
		(property "Value" "SQS401EN-T1_BE3"
			(at 137.16 113.03 0)
			(effects
				(font
					(size 1.27 1.27)
					(thickness 0.15)
				)
				(justify left bottom)
				(hide yes)
			)
		)
		(property "Footprint" "antmicro-footprints:Vishay_PowerPAK_1212-8_Single"
			(at 134.62 113.03 0)
			(effects
				(font
					(size 1.27 1.27)
					(thickness 0.15)
				)
				(justify left bottom)
				(hide yes)
			)
		)
		(property "Datasheet" "https://www.vishay.com/docs/65529/sqs401en.pdf"
			(at 132.08 113.03 0)
			(effects
				(font
					(size 1.27 1.27)
					(thickness 0.15)
				)
				(justify left bottom)
				(hide yes)
			)
		)
		(property "Description" ""
			(at 147.32 128.27 0)
			(effects
				(font
					(size 1.27 1.27)
				)
				(hide yes)
			)
		)
		(property "MPN" "SQS401EN-T1_BE3"
			(at 149.86 118.11 90)
			(effects
				(font
					(size 1.27 1.27)
					(thickness 0.15)
				)
			)
		)
		(property "Manufacturer" "Vishay"
			(at 129.54 113.03 0)
			(effects
				(font
					(size 1.27 1.27)
					(thickness 0.15)
				)
				(justify left bottom)
				(hide yes)
			)
		)
		(property "Author" "Antmicro"
			(at 127 113.03 0)
			(effects
				(font
					(size 1.27 1.27)
					(thickness 0.15)
				)
				(justify left bottom)
				(hide yes)
			)
		)
		(property "License" "Apache-2.0"
			(at 124.46 113.03 0)
			(effects
				(font
					(size 1.27 1.27)
					(thickness 0.15)
				)
				(justify left bottom)
				(hide yes)
			)
		)
		(pin "1"
		)
		(pin "2"
		)
		(pin "3"
		)
		(pin "4"
		)
		(pin "5"
		)
		(instances
			(project "cm4-baseboard"
				(path ""
					(reference "Q307")
					(unit 1)
				)
			)
		)
	)
	(symbol
		(lib_id "antmicroTestPoints:TP_0.75mm_SMD")
		(at 389.89 177.8 0)
		(unit 1)
		(exclude_from_sim no)
		(in_bom no)
		(on_board yes)
		(dnp no)
		(fields_autoplaced yes)
		(property "Reference" "TP307"
			(at 394.97 177.7999 0)
			(effects
				(font
					(size 1.27 1.27)
				)
				(justify left)
			)
		)
		(property "Value" "TP_0.75mm_SMD"
			(at 389.89 180.34 0)
			(effects
				(font
					(size 1.27 1.27)
				)
				(justify left bottom)
				(hide yes)
			)
		)
		(property "Footprint" "antmicro-footprints:TP_SMD_0.75mm"
			(at 394.97 172.72 0)
			(effects
				(font
					(size 1.524 1.524)
				)
				(justify left bottom)
				(hide yes)
			)
		)
		(property "Datasheet" ""
			(at 394.97 170.18 0)
			(effects
				(font
					(size 1.524 1.524)
				)
				(justify left bottom)
				(hide yes)
			)
		)
		(property "Description" ""
			(at 389.89 177.8 0)
			(effects
				(font
					(size 1.27 1.27)
				)
				(hide yes)
			)
		)
		(property "MPN" ""
			(at 389.89 177.8 0)
			(effects
				(font
					(size 1.27 1.27)
				)
				(hide yes)
			)
		)
		(property "Manufacturer" ""
			(at 389.89 177.8 0)
			(effects
				(font
					(size 1.27 1.27)
				)
				(hide yes)
			)
		)
		(property "Author" "Antmicro"
			(at 405.13 193.04 0)
			(effects
				(font
					(size 1.27 1.27)
					(thickness 0.15)
				)
				(justify left bottom)
				(hide yes)
			)
		)
		(property "License" "Apache-2.0"
			(at 405.13 195.58 0)
			(effects
				(font
					(size 1.27 1.27)
					(thickness 0.15)
				)
				(justify left bottom)
				(hide yes)
			)
		)
		(pin "1"
		)
		(instances
			(project "cm4-baseboard"
				(path ""
					(reference "TP307")
					(unit 1)
				)
			)
		)
	)
	(symbol
		(lib_id "antmicroCapacitorsmisc:C_22u_25V_0805")
		(at 345.44 181.61 90)
		(mirror x)
		(unit 1)
		(exclude_from_sim no)
		(in_bom yes)
		(on_board yes)
		(dnp no)
		(fields_autoplaced yes)
		(property "Reference" "C313"
			(at 347.98 181.6163 90)
			(effects
				(font
					(size 1.27 1.27)
				)
				(justify right)
			)
		)
		(property "Value" "C_22u_25V_0805"
			(at 349.25 181.61 0)
			(effects
				(font
					(size 1.27 1.27)
				)
				(justify left bottom)
				(hide yes)
			)
		)
		(property "Footprint" "antmicro-footprints:C_0805_2012Metric"
			(at 340.36 186.69 0)
			(effects
				(font
					(size 1.524 1.524)
				)
				(justify left bottom)
				(hide yes)
			)
		)
		(property "Datasheet" "https://product.samsungsem.com/mlcc/CL21A226MAYNNN.do"
			(at 345.44 181.61 0)
			(effects
				(font
					(size 1.27 1.27)
				)
				(justify left bottom)
				(hide yes)
			)
		)
		(property "Description" ""
			(at 345.44 181.61 0)
			(effects
				(font
					(size 1.27 1.27)
				)
				(hide yes)
			)
		)
		(property "Manufacturer" "Samsung Electro-Mechanics"
			(at 335.28 186.69 0)
			(effects
				(font
					(size 1.524 1.524)
				)
				(justify left bottom)
				(hide yes)
			)
		)
		(property "MPN" "CL21A226MAYNNNE"
			(at 337.82 186.69 0)
			(effects
				(font
					(size 1.524 1.524)
				)
				(justify left bottom)
				(hide yes)
			)
		)
		(property "Val" "22u"
			(at 347.98 184.1563 90)
			(effects
				(font
					(size 1.27 1.27)
				)
				(justify right)
			)
		)
		(property "License" "Apache-2.0"
			(at 368.3 201.93 0)
			(effects
				(font
					(size 1.27 1.27)
					(thickness 0.15)
				)
				(justify left bottom)
				(hide yes)
			)
		)
		(property "Author" "Antmicro"
			(at 370.84 201.93 0)
			(effects
				(font
					(size 1.27 1.27)
					(thickness 0.15)
				)
				(justify left bottom)
				(hide yes)
			)
		)
		(property "Voltage" "25V"
			(at 347.98 186.6963 90)
			(effects
				(font
					(size 1.27 1.27)
				)
				(justify right)
			)
		)
		(property "Dielectric" "X5R"
			(at 375.92 201.93 0)
			(effects
				(font
					(size 1.27 1.27)
				)
				(justify left bottom)
				(hide yes)
			)
		)
		(property "Public" "False"
			(at 378.46 201.93 0)
			(effects
				(font
					(size 1.27 1.27)
				)
				(justify left bottom)
				(hide yes)
			)
		)
		(pin "1"
		)
		(pin "2"
		)
		(instances
			(project "cm4-baseboard"
				(path ""
					(reference "C313")
					(unit 1)
				)
			)
		)
	)
	(symbol
		(lib_id "antmicropower:GND")
		(at 388.62 130.81 0)
		(mirror y)
		(unit 1)
		(exclude_from_sim no)
		(in_bom yes)
		(on_board yes)
		(dnp no)
		(fields_autoplaced yes)
		(property "Reference" "#PWR0342"
			(at 379.73 133.35 0)
			(effects
				(font
					(size 1.27 1.27)
					(thickness 0.15)
				)
				(justify left bottom)
				(hide yes)
			)
		)
		(property "Value" "GND"
			(at 390.6302 135.89 0)
			(effects
				(font
					(size 1.27 1.27)
					(thickness 0.15)
				)
				(justify left bottom)
			)
		)
		(property "Footprint" ""
			(at 379.73 138.43 0)
			(effects
				(font
					(size 1.27 1.27)
					(thickness 0.15)
				)
				(justify left bottom)
				(hide yes)
			)
		)
		(property "Datasheet" ""
			(at 379.73 143.51 0)
			(effects
				(font
					(size 1.27 1.27)
					(thickness 0.15)
				)
				(justify left bottom)
				(hide yes)
			)
		)
		(property "Description" ""
			(at 388.62 130.81 0)
			(effects
				(font
					(size 1.27 1.27)
				)
				(hide yes)
			)
		)
		(property "Author" "Antmicro"
			(at 379.73 138.43 0)
			(effects
				(font
					(size 1.27 1.27)
					(thickness 0.15)
				)
				(justify left bottom)
				(hide yes)
			)
		)
		(property "License" "Apache-2.0"
			(at 379.73 140.97 0)
			(effects
				(font
					(size 1.27 1.27)
					(thickness 0.15)
				)
				(justify left bottom)
				(hide yes)
			)
		)
		(pin "1"
		)
		(instances
			(project "cm4-baseboard"
				(path ""
					(reference "#PWR0342")
					(unit 1)
				)
			)
		)
	)
	(symbol
		(lib_id "antmicroPMICORControllersIdealDiodes:DZDH0401DW")
		(at 67.31 182.88 0)
		(unit 1)
		(exclude_from_sim no)
		(in_bom yes)
		(on_board yes)
		(dnp no)
		(fields_autoplaced yes)
		(property "Reference" "Q302"
			(at 75.565 176.53 0)
			(effects
				(font
					(size 1.27 1.27)
					(thickness 0.15)
				)
			)
		)
		(property "Value" "DZDH0401DW"
			(at 75.565 179.07 0)
			(effects
				(font
					(size 1.27 1.27)
					(thickness 0.15)
				)
				(hide yes)
			)
		)
		(property "Footprint" "antmicro-footprints:SOT-363"
			(at 97.79 193.04 0)
			(effects
				(font
					(size 1.27 1.27)
					(thickness 0.15)
				)
				(justify left bottom)
				(hide yes)
			)
		)
		(property "Datasheet" "https://www.mouser.com/datasheet/2/115/DIOD_S_A0011803041_1-2543705.pdf"
			(at 97.79 195.58 0)
			(effects
				(font
					(size 1.27 1.27)
					(thickness 0.15)
				)
				(justify left bottom)
				(hide yes)
			)
		)
		(property "Description" ""
			(at 67.31 182.88 0)
			(effects
				(font
					(size 1.27 1.27)
				)
				(hide yes)
			)
		)
		(property "MPN" "DZDH0401DW"
			(at 75.565 179.07 0)
			(effects
				(font
					(size 1.27 1.27)
					(thickness 0.15)
				)
			)
		)
		(property "Manufacturer" "Diodes Incorporated"
			(at 97.79 200.66 0)
			(effects
				(font
					(size 1.27 1.27)
					(thickness 0.15)
				)
				(justify left bottom)
				(hide yes)
			)
		)
		(property "Author" "Antmicro"
			(at 97.79 203.2 0)
			(effects
				(font
					(size 1.27 1.27)
					(thickness 0.15)
				)
				(justify left bottom)
				(hide yes)
			)
		)
		(property "License" "Apache-2.0"
			(at 97.79 205.74 0)
			(effects
				(font
					(size 1.27 1.27)
					(thickness 0.15)
				)
				(justify left bottom)
				(hide yes)
			)
		)
		(pin "4"
		)
		(pin "6"
		)
		(pin "2"
		)
		(pin "3"
		)
		(pin "1"
		)
		(pin "5"
		)
		(instances
			(project "cm4-baseboard"
				(path ""
					(reference "Q302")
					(unit 1)
				)
			)
		)
	)
	(symbol
		(lib_id "antmicroTVSDiodes:SMF4L15A")
		(at 185.42 130.81 270)
		(unit 1)
		(exclude_from_sim no)
		(in_bom yes)
		(on_board yes)
		(dnp no)
		(fields_autoplaced yes)
		(property "Reference" "D303"
			(at 187.325 132.08 90)
			(effects
				(font
					(size 1.27 1.27)
				)
				(justify left)
			)
		)
		(property "Value" "SMF4L15A"
			(at 182.88 134.62 90)
			(effects
				(font
					(size 1.27 1.27)
					(thickness 0.15)
				)
				(justify right)
				(hide yes)
			)
		)
		(property "Footprint" "antmicro-footprints:SOD-123FL"
			(at 175.26 157.48 0)
			(effects
				(font
					(size 1.27 1.27)
					(thickness 0.15)
				)
				(justify left bottom)
				(hide yes)
			)
		)
		(property "Datasheet" "https://www.littelfuse.com/media?resourcetype=datasheets&itemid=d2ba8fab-1de3-4176-8530-f36ecb0b8799&filename=smf4l"
			(at 172.72 157.48 0)
			(effects
				(font
					(size 1.27 1.27)
					(thickness 0.15)
				)
				(justify left bottom)
				(hide yes)
			)
		)
		(property "Description" ""
			(at 185.42 130.81 0)
			(effects
				(font
					(size 1.27 1.27)
				)
				(hide yes)
			)
		)
		(property "Manufacturer" "Littelfuse"
			(at 167.64 157.48 0)
			(effects
				(font
					(size 1.27 1.27)
					(thickness 0.15)
				)
				(justify left bottom)
				(hide yes)
			)
		)
		(property "MPN" "SMF4L15A"
			(at 187.325 134.62 90)
			(effects
				(font
					(size 1.27 1.27)
					(thickness 0.15)
				)
				(justify left)
			)
		)
		(property "Author" "Antmicro"
			(at 165.1 157.48 0)
			(effects
				(font
					(size 1.27 1.27)
					(thickness 0.15)
				)
				(justify left bottom)
				(hide yes)
			)
		)
		(property "License" "Apache-2.0"
			(at 162.56 157.48 0)
			(effects
				(font
					(size 1.27 1.27)
					(thickness 0.15)
				)
				(justify left bottom)
				(hide yes)
			)
		)
		(pin "1"
		)
		(pin "2"
		)
		(instances
			(project "cm4-baseboard"
				(path ""
					(reference "D303")
					(unit 1)
				)
			)
		)
	)
	(symbol
		(lib_id "antmicroResistors0402:R_100k_0402")
		(at 289.56 140.97 90)
		(unit 1)
		(exclude_from_sim no)
		(in_bom yes)
		(on_board yes)
		(dnp no)
		(property "Reference" "R315"
			(at 288.29 137.16 90)
			(effects
				(font
					(size 1.27 1.27)
				)
				(justify left)
			)
		)
		(property "Value" "R_100k_0402"
			(at 293.37 140.97 0)
			(effects
				(font
					(size 1.27 1.27)
					(thickness 0.15)
				)
				(justify left bottom)
				(hide yes)
			)
		)
		(property "Footprint" "antmicro-footprints:R_0402_1005Metric"
			(at 284.48 135.89 0)
			(effects
				(font
					(size 1.27 1.27)
					(thickness 0.15)
				)
				(justify left bottom)
				(hide yes)
			)
		)
		(property "Datasheet" "https://www.bourns.com/docs/product-datasheets/cr.pdf"
			(at 289.56 140.97 0)
			(effects
				(font
					(size 1.27 1.27)
					(thickness 0.15)
				)
				(justify left bottom)
				(hide yes)
			)
		)
		(property "Description" ""
			(at 289.56 140.97 0)
			(effects
				(font
					(size 1.27 1.27)
				)
				(hide yes)
			)
		)
		(property "Manufacturer" "Bourns"
			(at 279.4 135.89 0)
			(effects
				(font
					(size 1.27 1.27)
					(thickness 0.15)
				)
				(justify left bottom)
				(hide yes)
			)
		)
		(property "MPN" "CR0402-FX-1003GLF"
			(at 281.94 135.89 0)
			(effects
				(font
					(size 1.27 1.27)
					(thickness 0.15)
				)
				(justify left bottom)
				(hide yes)
			)
		)
		(property "Val" "100k"
			(at 288.29 139.7 90)
			(effects
				(font
					(size 1.27 1.27)
					(thickness 0.15)
				)
				(justify left)
			)
		)
		(property "License" "Apache-2.0"
			(at 314.96 120.65 0)
			(effects
				(font
					(size 1.27 1.27)
					(thickness 0.15)
				)
				(justify left bottom)
				(hide yes)
			)
		)
		(property "Author" "Antmicro"
			(at 317.5 120.65 0)
			(effects
				(font
					(size 1.27 1.27)
					(thickness 0.15)
				)
				(justify left bottom)
				(hide yes)
			)
		)
		(property "Tolerance" "1%"
			(at 299.72 120.65 0)
			(effects
				(font
					(size 1.27 1.27)
				)
				(justify left bottom)
				(hide yes)
			)
		)
		(pin "1"
		)
		(pin "2"
		)
		(instances
			(project "cm4-baseboard"
				(path ""
					(reference "R315")
					(unit 1)
				)
			)
		)
	)
	(symbol
		(lib_id "antmicroCapacitors0402:C_100n_0402")
		(at 163.83 129.54 90)
		(unit 1)
		(exclude_from_sim no)
		(in_bom yes)
		(on_board yes)
		(dnp no)
		(fields_autoplaced yes)
		(property "Reference" "C302"
			(at 166.37 125.7235 90)
			(effects
				(font
					(size 1.27 1.27)
				)
				(justify right)
			)
		)
		(property "Value" "C_100n_0402"
			(at 167.64 129.54 0)
			(effects
				(font
					(size 1.27 1.27)
				)
				(justify left bottom)
				(hide yes)
			)
		)
		(property "Footprint" "antmicro-footprints:C_0402_1005Metric"
			(at 158.75 124.46 0)
			(effects
				(font
					(size 1.524 1.524)
				)
				(justify left bottom)
				(hide yes)
			)
		)
		(property "Datasheet" "https://www.murata.com/products/productdetail?partno=GRM155R61H104KE14%23"
			(at 163.83 129.54 0)
			(effects
				(font
					(size 1.27 1.27)
				)
				(justify left bottom)
				(hide yes)
			)
		)
		(property "Description" ""
			(at 163.83 129.54 0)
			(effects
				(font
					(size 1.27 1.27)
				)
				(hide yes)
			)
		)
		(property "Manufacturer" "Murata"
			(at 153.67 124.46 0)
			(effects
				(font
					(size 1.524 1.524)
				)
				(justify left bottom)
				(hide yes)
			)
		)
		(property "MPN" "GRM155R61H104KE14D"
			(at 156.21 124.46 0)
			(effects
				(font
					(size 1.524 1.524)
				)
				(justify left bottom)
				(hide yes)
			)
		)
		(property "Val" "100n"
			(at 166.37 128.2635 90)
			(effects
				(font
					(size 1.27 1.27)
				)
				(justify right)
			)
		)
		(property "License" "Apache-2.0"
			(at 186.69 109.22 0)
			(effects
				(font
					(size 1.27 1.27)
					(thickness 0.15)
				)
				(justify left bottom)
				(hide yes)
			)
		)
		(property "Author" "Antmicro"
			(at 189.23 109.22 0)
			(effects
				(font
					(size 1.27 1.27)
					(thickness 0.15)
				)
				(justify left bottom)
				(hide yes)
			)
		)
		(property "Voltage" "50V"
			(at 191.77 109.22 0)
			(effects
				(font
					(size 1.27 1.27)
				)
				(justify left bottom)
				(hide yes)
			)
		)
		(property "Dielectric" "X5R"
			(at 194.31 109.22 0)
			(effects
				(font
					(size 1.27 1.27)
				)
				(justify left bottom)
				(hide yes)
			)
		)
		(pin "1"
		)
		(pin "2"
		)
		(instances
			(project "cm4-baseboard"
				(path ""
					(reference "C302")
					(unit 1)
				)
			)
		)
	)
	(symbol
		(lib_id "antmicroResistors0603:R_0R_22.4A_0603")
		(at 73.66 111.76 0)
		(unit 1)
		(exclude_from_sim no)
		(in_bom no)
		(on_board yes)
		(dnp yes)
		(property "Reference" "R328"
			(at 76.2 109.22 0)
			(effects
				(font
					(size 1.27 1.27)
				)
			)
		)
		(property "Value" "R_0R_22.4A_0603"
			(at 73.66 115.57 0)
			(effects
				(font
					(size 1.27 1.27)
				)
				(justify left bottom)
				(hide yes)
			)
		)
		(property "Footprint" "antmicro-footprints:R_0603_1608Metric"
			(at 78.74 106.68 0)
			(effects
				(font
					(size 1.524 1.524)
				)
				(justify left bottom)
				(hide yes)
			)
		)
		(property "Datasheet" "https://fscdn.rohm.com/en/products/databook/datasheet/passive/resistor/chip_resistor/pmr-jpw-e.pdf"
			(at 73.66 111.76 0)
			(effects
				(font
					(size 1.27 1.27)
				)
				(justify left bottom)
				(hide yes)
			)
		)
		(property "Description" ""
			(at 73.66 111.76 0)
			(effects
				(font
					(size 1.27 1.27)
				)
				(hide yes)
			)
		)
		(property "Manufacturer" "ROHM Semiconductor"
			(at 78.74 101.6 0)
			(effects
				(font
					(size 1.524 1.524)
				)
				(justify left bottom)
				(hide yes)
			)
		)
		(property "MPN" "PMR03EZPJ000"
			(at 78.74 104.14 0)
			(effects
				(font
					(size 1.524 1.524)
				)
				(justify left bottom)
				(hide yes)
			)
		)
		(property "Val" "0R"
			(at 71.755 110.49 0)
			(effects
				(font
					(size 1.27 1.27)
				)
			)
		)
		(property "Author" "Antmicro"
			(at 96.52 134.62 0)
			(effects
				(font
					(size 1.27 1.27)
					(thickness 0.15)
				)
				(justify left bottom)
				(hide yes)
			)
		)
		(property "License" "Apache-2.0"
			(at 96.52 137.16 0)
			(effects
				(font
					(size 1.27 1.27)
					(thickness 0.15)
				)
				(justify left bottom)
				(hide yes)
			)
		)
		(property "Max. Curr." "22.4A"
			(at 81.915 110.49 0)
			(effects
				(font
					(size 1.27 1.27)
					(thickness 0.15)
				)
			)
		)
		(property "Tolerance" "template_tolerance"
			(at 93.98 121.92 0)
			(effects
				(font
					(size 1.27 1.27)
				)
				(justify left bottom)
				(hide yes)
			)
		)
		(pin "1"
		)
		(pin "2"
		)
		(instances
			(project "cm4-baseboard"
				(path ""
					(reference "R328")
					(unit 1)
				)
			)
		)
	)
	(symbol
		(lib_id "antmicroCapacitorsmisc:C_22u_25V_0805")
		(at 260.35 113.03 90)
		(mirror x)
		(unit 1)
		(exclude_from_sim no)
		(in_bom yes)
		(on_board yes)
		(dnp no)
		(fields_autoplaced yes)
		(property "Reference" "C303"
			(at 257.81 113.0362 90)
			(effects
				(font
					(size 1.27 1.27)
				)
				(justify left)
			)
		)
		(property "Value" "C_22u_25V_0805"
			(at 264.16 113.03 0)
			(effects
				(font
					(size 1.27 1.27)
				)
				(justify left bottom)
				(hide yes)
			)
		)
		(property "Footprint" "antmicro-footprints:C_0805_2012Metric"
			(at 255.27 118.11 0)
			(effects
				(font
					(size 1.524 1.524)
				)
				(justify left bottom)
				(hide yes)
			)
		)
		(property "Datasheet" "https://product.samsungsem.com/mlcc/CL21A226MAYNNN.do"
			(at 260.35 113.03 0)
			(effects
				(font
					(size 1.27 1.27)
				)
				(justify left bottom)
				(hide yes)
			)
		)
		(property "Description" ""
			(at 260.35 113.03 0)
			(effects
				(font
					(size 1.27 1.27)
				)
				(hide yes)
			)
		)
		(property "Manufacturer" "Samsung Electro-Mechanics"
			(at 250.19 118.11 0)
			(effects
				(font
					(size 1.524 1.524)
				)
				(justify left bottom)
				(hide yes)
			)
		)
		(property "MPN" "CL21A226MAYNNNE"
			(at 252.73 118.11 0)
			(effects
				(font
					(size 1.524 1.524)
				)
				(justify left bottom)
				(hide yes)
			)
		)
		(property "Val" "22u"
			(at 257.81 115.5762 90)
			(effects
				(font
					(size 1.27 1.27)
				)
				(justify left)
			)
		)
		(property "License" "Apache-2.0"
			(at 283.21 133.35 0)
			(effects
				(font
					(size 1.27 1.27)
					(thickness 0.15)
				)
				(justify left bottom)
				(hide yes)
			)
		)
		(property "Author" "Antmicro"
			(at 285.75 133.35 0)
			(effects
				(font
					(size 1.27 1.27)
					(thickness 0.15)
				)
				(justify left bottom)
				(hide yes)
			)
		)
		(property "Voltage" "25V"
			(at 257.81 118.1162 90)
			(effects
				(font
					(size 1.27 1.27)
				)
				(justify left)
			)
		)
		(property "Dielectric" "X5R"
			(at 290.83 133.35 0)
			(effects
				(font
					(size 1.27 1.27)
				)
				(justify left bottom)
				(hide yes)
			)
		)
		(property "Public" "False"
			(at 293.37 133.35 0)
			(effects
				(font
					(size 1.27 1.27)
				)
				(justify left bottom)
				(hide yes)
			)
		)
		(pin "1"
		)
		(pin "2"
		)
		(instances
			(project "cm4-baseboard"
				(path ""
					(reference "C303")
					(unit 1)
				)
			)
		)
	)
	(symbol
		(lib_id "antmicropower:GND")
		(at 36.83 130.81 0)
		(unit 1)
		(exclude_from_sim no)
		(in_bom yes)
		(on_board yes)
		(dnp no)
		(fields_autoplaced yes)
		(property "Reference" "#PWR0301"
			(at 36.83 137.16 0)
			(effects
				(font
					(size 1.27 1.27)
				)
				(justify left bottom)
				(hide yes)
			)
		)
		(property "Value" "GND"
			(at 36.83 135.89 0)
			(effects
				(font
					(size 1.27 1.27)
				)
			)
		)
		(property "Footprint" ""
			(at 45.72 138.43 0)
			(effects
				(font
					(size 1.27 1.27)
					(thickness 0.15)
				)
				(justify left bottom)
				(hide yes)
			)
		)
		(property "Datasheet" ""
			(at 45.72 143.51 0)
			(effects
				(font
					(size 1.27 1.27)
					(thickness 0.15)
				)
				(justify left bottom)
				(hide yes)
			)
		)
		(property "Description" ""
			(at 36.83 130.81 0)
			(effects
				(font
					(size 1.27 1.27)
				)
				(hide yes)
			)
		)
		(property "Author" "Antmicro"
			(at 45.72 138.43 0)
			(effects
				(font
					(size 1.27 1.27)
					(thickness 0.15)
				)
				(justify left bottom)
				(hide yes)
			)
		)
		(property "License" "Apache-2.0"
			(at 45.72 140.97 0)
			(effects
				(font
					(size 1.27 1.27)
					(thickness 0.15)
				)
				(justify left bottom)
				(hide yes)
			)
		)
		(pin "1"
		)
		(instances
			(project "cm4-baseboard"
				(path ""
					(reference "#PWR0301")
					(unit 1)
				)
			)
		)
	)
	(symbol
		(lib_id "antmicropower:VCC")
		(at 261.62 218.44 0)
		(unit 1)
		(exclude_from_sim no)
		(in_bom yes)
		(on_board yes)
		(dnp no)
		(fields_autoplaced yes)
		(property "Reference" "#PWR0317"
			(at 261.62 222.25 0)
			(effects
				(font
					(size 1.27 1.27)
				)
				(justify left bottom)
				(hide yes)
			)
		)
		(property "Value" "VCC"
			(at 261.62 213.36 0)
			(effects
				(font
					(size 1.27 1.27)
				)
			)
		)
		(property "Footprint" ""
			(at 261.62 218.44 0)
			(effects
				(font
					(size 1.27 1.27)
				)
				(justify left bottom)
				(hide yes)
			)
		)
		(property "Datasheet" ""
			(at 261.62 218.44 0)
			(effects
				(font
					(size 1.27 1.27)
				)
				(justify left bottom)
				(hide yes)
			)
		)
		(property "Description" ""
			(at 261.62 218.44 0)
			(effects
				(font
					(size 1.27 1.27)
				)
				(hide yes)
			)
		)
		(pin "1"
		)
		(instances
			(project "cm4-baseboard"
				(path ""
					(reference "#PWR0317")
					(unit 1)
				)
			)
		)
	)
	(symbol
		(lib_id "antmicropower:GND")
		(at 293.37 137.16 0)
		(unit 1)
		(exclude_from_sim no)
		(in_bom yes)
		(on_board yes)
		(dnp no)
		(property "Reference" "#PWR0326"
			(at 293.37 143.51 0)
			(effects
				(font
					(size 1.27 1.27)
				)
				(justify left bottom)
				(hide yes)
			)
		)
		(property "Value" "GND"
			(at 293.37 140.97 0)
			(effects
				(font
					(size 1.27 1.27)
				)
			)
		)
		(property "Footprint" ""
			(at 302.26 144.78 0)
			(effects
				(font
					(size 1.27 1.27)
					(thickness 0.15)
				)
				(justify left bottom)
				(hide yes)
			)
		)
		(property "Datasheet" ""
			(at 302.26 149.86 0)
			(effects
				(font
					(size 1.27 1.27)
					(thickness 0.15)
				)
				(justify left bottom)
				(hide yes)
			)
		)
		(property "Description" ""
			(at 293.37 137.16 0)
			(effects
				(font
					(size 1.27 1.27)
				)
				(hide yes)
			)
		)
		(property "Author" "Antmicro"
			(at 302.26 144.78 0)
			(effects
				(font
					(size 1.27 1.27)
					(thickness 0.15)
				)
				(justify left bottom)
				(hide yes)
			)
		)
		(property "License" "Apache-2.0"
			(at 302.26 147.32 0)
			(effects
				(font
					(size 1.27 1.27)
					(thickness 0.15)
				)
				(justify left bottom)
				(hide yes)
			)
		)
		(pin "1"
		)
		(instances
			(project "cm4-baseboard"
				(path ""
					(reference "#PWR0326")
					(unit 1)
				)
			)
		)
	)
	(symbol
		(lib_id "antmicropower:GND")
		(at 147.32 144.78 0)
		(unit 1)
		(exclude_from_sim no)
		(in_bom yes)
		(on_board yes)
		(dnp no)
		(fields_autoplaced yes)
		(property "Reference" "#PWR0309"
			(at 147.32 151.13 0)
			(effects
				(font
					(size 1.27 1.27)
				)
				(justify left bottom)
				(hide yes)
			)
		)
		(property "Value" "GND"
			(at 147.32 149.86 0)
			(effects
				(font
					(size 1.27 1.27)
				)
			)
		)
		(property "Footprint" ""
			(at 156.21 152.4 0)
			(effects
				(font
					(size 1.27 1.27)
					(thickness 0.15)
				)
				(justify left bottom)
				(hide yes)
			)
		)
		(property "Datasheet" ""
			(at 156.21 157.48 0)
			(effects
				(font
					(size 1.27 1.27)
					(thickness 0.15)
				)
				(justify left bottom)
				(hide yes)
			)
		)
		(property "Description" ""
			(at 147.32 144.78 0)
			(effects
				(font
					(size 1.27 1.27)
				)
				(hide yes)
			)
		)
		(property "Author" "Antmicro"
			(at 156.21 152.4 0)
			(effects
				(font
					(size 1.27 1.27)
					(thickness 0.15)
				)
				(justify left bottom)
				(hide yes)
			)
		)
		(property "License" "Apache-2.0"
			(at 156.21 154.94 0)
			(effects
				(font
					(size 1.27 1.27)
					(thickness 0.15)
				)
				(justify left bottom)
				(hide yes)
			)
		)
		(pin "1"
		)
		(instances
			(project "cm4-baseboard"
				(path ""
					(reference "#PWR0309")
					(unit 1)
				)
			)
		)
	)
	(symbol
		(lib_id "antmicroResistors0402:R_2k_0402")
		(at 335.28 129.54 270)
		(mirror x)
		(unit 1)
		(exclude_from_sim no)
		(in_bom yes)
		(on_board yes)
		(dnp no)
		(property "Reference" "R317"
			(at 334.01 125.73 90)
			(effects
				(font
					(size 1.27 1.27)
					(thickness 0.15)
				)
				(justify right)
			)
		)
		(property "Value" "R_2k_0402"
			(at 322.58 109.22 0)
			(effects
				(font
					(size 1.27 1.27)
					(thickness 0.15)
				)
				(justify left bottom)
				(hide yes)
			)
		)
		(property "Footprint" "antmicro-footprints:R_0402_1005Metric"
			(at 320.04 109.22 0)
			(effects
				(font
					(size 1.27 1.27)
					(thickness 0.15)
				)
				(justify left bottom)
				(hide yes)
			)
		)
		(property "Datasheet" "https://www.bourns.com/docs/product-datasheets/cr.pdf"
			(at 317.5 109.22 0)
			(effects
				(font
					(size 1.27 1.27)
					(thickness 0.15)
				)
				(justify left bottom)
				(hide yes)
			)
		)
		(property "Description" ""
			(at 335.28 129.54 0)
			(effects
				(font
					(size 1.27 1.27)
				)
				(hide yes)
			)
		)
		(property "MPN" "CR0402-FX-2001GLF"
			(at 314.96 109.22 0)
			(effects
				(font
					(size 1.27 1.27)
					(thickness 0.15)
				)
				(justify left bottom)
				(hide yes)
			)
		)
		(property "Manufacturer" "Bourns"
			(at 312.42 109.22 0)
			(effects
				(font
					(size 1.27 1.27)
					(thickness 0.15)
				)
				(justify left bottom)
				(hide yes)
			)
		)
		(property "License" "Apache-2.0"
			(at 309.88 109.22 0)
			(effects
				(font
					(size 1.27 1.27)
					(thickness 0.15)
				)
				(justify left bottom)
				(hide yes)
			)
		)
		(property "Author" "Antmicro"
			(at 307.34 109.22 0)
			(effects
				(font
					(size 1.27 1.27)
					(thickness 0.15)
				)
				(justify left bottom)
				(hide yes)
			)
		)
		(property "Val" "2k"
			(at 334.01 128.27 90)
			(effects
				(font
					(size 1.27 1.27)
					(thickness 0.15)
				)
				(justify right)
			)
		)
		(property "Tolerance" "1%"
			(at 325.12 109.22 0)
			(effects
				(font
					(size 1.27 1.27)
				)
				(justify left bottom)
				(hide yes)
			)
		)
		(pin "2"
		)
		(pin "1"
		)
		(instances
			(project "cm4-baseboard"
				(path ""
					(reference "R317")
					(unit 1)
				)
			)
		)
	)
	(symbol
		(lib_id "antmicroResistors0402:R_6k8_0402")
		(at 334.01 228.6 90)
		(unit 1)
		(exclude_from_sim no)
		(in_bom yes)
		(on_board yes)
		(dnp no)
		(fields_autoplaced yes)
		(property "Reference" "R320"
			(at 336.55 224.79 90)
			(effects
				(font
					(size 1.27 1.27)
					(thickness 0.15)
				)
				(justify right)
			)
		)
		(property "Value" "R_6k8_0402"
			(at 346.71 208.28 0)
			(effects
				(font
					(size 1.27 1.27)
					(thickness 0.15)
				)
				(justify left bottom)
				(hide yes)
			)
		)
		(property "Footprint" "antmicro-footprints:R_0402_1005Metric"
			(at 349.25 208.28 0)
			(effects
				(font
					(size 1.27 1.27)
					(thickness 0.15)
				)
				(justify left bottom)
				(hide yes)
			)
		)
		(property "Datasheet" "https://www.bourns.com/docs/product-datasheets/cr.pdf"
			(at 351.79 208.28 0)
			(effects
				(font
					(size 1.27 1.27)
					(thickness 0.15)
				)
				(justify left bottom)
				(hide yes)
			)
		)
		(property "Description" ""
			(at 334.01 228.6 0)
			(effects
				(font
					(size 1.27 1.27)
				)
				(hide yes)
			)
		)
		(property "MPN" "CR0402-FX-6801GLF"
			(at 354.33 208.28 0)
			(effects
				(font
					(size 1.27 1.27)
					(thickness 0.15)
				)
				(justify left bottom)
				(hide yes)
			)
		)
		(property "Manufacturer" "Bourns"
			(at 356.87 208.28 0)
			(effects
				(font
					(size 1.27 1.27)
					(thickness 0.15)
				)
				(justify left bottom)
				(hide yes)
			)
		)
		(property "License" "Apache-2.0"
			(at 359.41 208.28 0)
			(effects
				(font
					(size 1.27 1.27)
					(thickness 0.15)
				)
				(justify left bottom)
				(hide yes)
			)
		)
		(property "Author" "Antmicro"
			(at 361.95 208.28 0)
			(effects
				(font
					(size 1.27 1.27)
					(thickness 0.15)
				)
				(justify left bottom)
				(hide yes)
			)
		)
		(property "Val" "6k8"
			(at 336.55 227.33 90)
			(effects
				(font
					(size 1.27 1.27)
					(thickness 0.15)
				)
				(justify right)
			)
		)
		(property "Tolerance" "1%"
			(at 344.17 208.28 0)
			(effects
				(font
					(size 1.27 1.27)
				)
				(justify left bottom)
				(hide yes)
			)
		)
		(pin "2"
		)
		(pin "1"
		)
		(instances
			(project "cm4-baseboard"
				(path ""
					(reference "R320")
					(unit 1)
				)
			)
		)
	)
	(symbol
		(lib_id "antmicroResistors0402:R_15k_0402")
		(at 335.28 121.92 90)
		(unit 1)
		(exclude_from_sim no)
		(in_bom yes)
		(on_board yes)
		(dnp no)
		(property "Reference" "R316"
			(at 334.01 118.11 90)
			(effects
				(font
					(size 1.27 1.27)
				)
				(justify left)
			)
		)
		(property "Value" "R_15k_0402"
			(at 342.9 121.92 0)
			(effects
				(font
					(size 1.27 1.27)
				)
				(justify left bottom)
				(hide yes)
			)
		)
		(property "Footprint" "antmicro-footprints:R_0402_1005Metric"
			(at 330.2 116.84 0)
			(effects
				(font
					(size 1.524 1.524)
				)
				(justify left bottom)
				(hide yes)
			)
		)
		(property "Datasheet" "https://www.bourns.com/docs/product-datasheets/cr.pdf"
			(at 340.36 121.92 0)
			(effects
				(font
					(size 1.27 1.27)
				)
				(justify left bottom)
				(hide yes)
			)
		)
		(property "Description" ""
			(at 335.28 121.92 0)
			(effects
				(font
					(size 1.27 1.27)
				)
				(hide yes)
			)
		)
		(property "Manufacturer" "Bourns"
			(at 325.12 116.84 0)
			(effects
				(font
					(size 1.524 1.524)
				)
				(justify left bottom)
				(hide yes)
			)
		)
		(property "MPN" "CR0402-FX-1502GLF"
			(at 327.66 116.84 0)
			(effects
				(font
					(size 1.524 1.524)
				)
				(justify left bottom)
				(hide yes)
			)
		)
		(property "Val" "15k"
			(at 334.01 120.65 90)
			(effects
				(font
					(size 1.27 1.27)
				)
				(justify left)
			)
		)
		(property "License" "Apache-2.0"
			(at 360.68 101.6 0)
			(effects
				(font
					(size 1.27 1.27)
					(thickness 0.15)
				)
				(justify left bottom)
				(hide yes)
			)
		)
		(property "Author" "Antmicro"
			(at 363.22 101.6 0)
			(effects
				(font
					(size 1.27 1.27)
					(thickness 0.15)
				)
				(justify left bottom)
				(hide yes)
			)
		)
		(property "Tolerance" "1%"
			(at 345.44 101.6 0)
			(effects
				(font
					(size 1.27 1.27)
				)
				(justify left bottom)
				(hide yes)
			)
		)
		(pin "1"
		)
		(pin "2"
		)
		(instances
			(project "cm4-baseboard"
				(path ""
					(reference "R316")
					(unit 1)
				)
			)
		)
	)
	(symbol
		(lib_id "antmicropower:GND")
		(at 345.44 194.31 0)
		(unit 1)
		(exclude_from_sim no)
		(in_bom yes)
		(on_board yes)
		(dnp no)
		(fields_autoplaced yes)
		(property "Reference" "#PWR0333"
			(at 354.33 196.85 0)
			(effects
				(font
					(size 1.27 1.27)
					(thickness 0.15)
				)
				(justify left bottom)
				(hide yes)
			)
		)
		(property "Value" "GND"
			(at 343.4298 199.39 0)
			(effects
				(font
					(size 1.27 1.27)
					(thickness 0.15)
				)
				(justify left bottom)
			)
		)
		(property "Footprint" ""
			(at 354.33 201.93 0)
			(effects
				(font
					(size 1.27 1.27)
					(thickness 0.15)
				)
				(justify left bottom)
				(hide yes)
			)
		)
		(property "Datasheet" ""
			(at 354.33 207.01 0)
			(effects
				(font
					(size 1.27 1.27)
					(thickness 0.15)
				)
				(justify left bottom)
				(hide yes)
			)
		)
		(property "Description" ""
			(at 345.44 194.31 0)
			(effects
				(font
					(size 1.27 1.27)
				)
				(hide yes)
			)
		)
		(property "Author" "Antmicro"
			(at 354.33 201.93 0)
			(effects
				(font
					(size 1.27 1.27)
					(thickness 0.15)
				)
				(justify left bottom)
				(hide yes)
			)
		)
		(property "License" "Apache-2.0"
			(at 354.33 204.47 0)
			(effects
				(font
					(size 1.27 1.27)
					(thickness 0.15)
				)
				(justify left bottom)
				(hide yes)
			)
		)
		(pin "1"
		)
		(instances
			(project "cm4-baseboard"
				(path ""
					(reference "#PWR0333")
					(unit 1)
				)
			)
		)
	)
	(symbol
		(lib_id "antmicroTestPoints:TP_0.75mm_SMD")
		(at 49.53 209.55 90)
		(unit 1)
		(exclude_from_sim no)
		(in_bom no)
		(on_board yes)
		(dnp no)
		(fields_autoplaced yes)
		(property "Reference" "TP308"
			(at 51.435 206.3749 90)
			(effects
				(font
					(size 1.27 1.27)
				)
				(justify right)
			)
		)
		(property "Value" "TP_0.75mm_SMD"
			(at 52.07 209.55 0)
			(effects
				(font
					(size 1.27 1.27)
					(thickness 0.15)
				)
				(justify left bottom)
				(hide yes)
			)
		)
		(property "Footprint" "antmicro-footprints:TP_SMD_0.75mm"
			(at 44.45 204.47 0)
			(effects
				(font
					(size 1.27 1.27)
					(thickness 0.15)
				)
				(justify left bottom)
				(hide yes)
			)
		)
		(property "Datasheet" ""
			(at 41.91 204.47 0)
			(effects
				(font
					(size 1.27 1.27)
					(thickness 0.15)
				)
				(justify left bottom)
				(hide yes)
			)
		)
		(property "Description" ""
			(at 49.53 209.55 0)
			(effects
				(font
					(size 1.27 1.27)
				)
				(hide yes)
			)
		)
		(property "MPN" ""
			(at 49.53 209.55 0)
			(effects
				(font
					(size 1.27 1.27)
					(thickness 0.15)
				)
				(justify left bottom)
				(hide yes)
			)
		)
		(property "Manufacturer" ""
			(at 49.53 209.55 0)
			(effects
				(font
					(size 1.27 1.27)
					(thickness 0.15)
				)
				(justify left bottom)
				(hide yes)
			)
		)
		(property "Author" "Antmicro"
			(at 64.77 194.31 0)
			(effects
				(font
					(size 1.27 1.27)
					(thickness 0.15)
				)
				(justify left bottom)
				(hide yes)
			)
		)
		(property "License" "Apache-2.0"
			(at 67.31 194.31 0)
			(effects
				(font
					(size 1.27 1.27)
					(thickness 0.15)
				)
				(justify left bottom)
				(hide yes)
			)
		)
		(pin "1"
		)
		(instances
			(project "cm4-baseboard"
				(path ""
					(reference "TP308")
					(unit 1)
				)
			)
		)
	)
	(symbol
		(lib_id "antmicroResistors0402:R_33k_0402")
		(at 66.04 148.59 90)
		(unit 1)
		(exclude_from_sim no)
		(in_bom yes)
		(on_board yes)
		(dnp no)
		(property "Reference" "R301"
			(at 67.31 144.78 90)
			(effects
				(font
					(size 1.27 1.27)
					(thickness 0.15)
				)
				(justify right)
			)
		)
		(property "Value" "R_33k_0402"
			(at 78.74 128.27 0)
			(effects
				(font
					(size 1.27 1.27)
					(thickness 0.15)
				)
				(justify left bottom)
				(hide yes)
			)
		)
		(property "Footprint" "antmicro-footprints:R_0402_1005Metric"
			(at 81.28 128.27 0)
			(effects
				(font
					(size 1.27 1.27)
					(thickness 0.15)
				)
				(justify left bottom)
				(hide yes)
			)
		)
		(property "Datasheet" "https://www.bourns.com/docs/product-datasheets/cr.pdf"
			(at 83.82 128.27 0)
			(effects
				(font
					(size 1.27 1.27)
					(thickness 0.15)
				)
				(justify left bottom)
				(hide yes)
			)
		)
		(property "Description" ""
			(at 66.04 148.59 0)
			(effects
				(font
					(size 1.27 1.27)
				)
				(hide yes)
			)
		)
		(property "MPN" "CR0402-FX-3302GLF"
			(at 86.36 128.27 0)
			(effects
				(font
					(size 1.27 1.27)
					(thickness 0.15)
				)
				(justify left bottom)
				(hide yes)
			)
		)
		(property "Manufacturer" "Bourns"
			(at 88.9 128.27 0)
			(effects
				(font
					(size 1.27 1.27)
					(thickness 0.15)
				)
				(justify left bottom)
				(hide yes)
			)
		)
		(property "License" "Apache-2.0"
			(at 91.44 128.27 0)
			(effects
				(font
					(size 1.27 1.27)
					(thickness 0.15)
				)
				(justify left bottom)
				(hide yes)
			)
		)
		(property "Author" "Antmicro"
			(at 93.98 128.27 0)
			(effects
				(font
					(size 1.27 1.27)
					(thickness 0.15)
				)
				(justify left bottom)
				(hide yes)
			)
		)
		(property "Val" "33k"
			(at 67.31 147.32 90)
			(effects
				(font
					(size 1.27 1.27)
					(thickness 0.15)
				)
				(justify right)
			)
		)
		(property "Tolerance" "1%"
			(at 76.2 128.27 0)
			(effects
				(font
					(size 1.27 1.27)
				)
				(justify left bottom)
				(hide yes)
			)
		)
		(pin "2"
		)
		(pin "1"
		)
		(instances
			(project "cm4-baseboard"
				(path ""
					(reference "R301")
					(unit 1)
				)
			)
		)
	)
	(symbol
		(lib_id "antmicroCapacitors0402:C_1u_25V_0402")
		(at 137.16 129.54 90)
		(unit 1)
		(exclude_from_sim no)
		(in_bom yes)
		(on_board yes)
		(dnp no)
		(property "Reference" "C301"
			(at 132.08 124.46 90)
			(effects
				(font
					(size 1.27 1.27)
					(thickness 0.15)
				)
				(justify right)
			)
		)
		(property "Value" "C_1u_25V_0402"
			(at 147.32 109.22 0)
			(effects
				(font
					(size 1.27 1.27)
					(thickness 0.15)
				)
				(justify left bottom)
				(hide yes)
			)
		)
		(property "Footprint" "antmicro-footprints:C_0402_1005Metric"
			(at 149.86 109.22 0)
			(effects
				(font
					(size 1.27 1.27)
					(thickness 0.15)
				)
				(justify left bottom)
				(hide yes)
			)
		)
		(property "Datasheet" "https://www.murata.com/products/productdetail?partno=GRM155R61E105KE11%23"
			(at 152.4 109.22 0)
			(effects
				(font
					(size 1.27 1.27)
					(thickness 0.15)
				)
				(justify left bottom)
				(hide yes)
			)
		)
		(property "Description" ""
			(at 137.16 129.54 0)
			(effects
				(font
					(size 1.27 1.27)
				)
				(hide yes)
			)
		)
		(property "MPN" "GRM155R61E105KE11J"
			(at 154.94 109.22 0)
			(effects
				(font
					(size 1.27 1.27)
					(thickness 0.15)
				)
				(justify left bottom)
				(hide yes)
			)
		)
		(property "Manufacturer" "Murata"
			(at 157.48 109.22 0)
			(effects
				(font
					(size 1.27 1.27)
					(thickness 0.15)
				)
				(justify left bottom)
				(hide yes)
			)
		)
		(property "License" "Apache-2.0"
			(at 160.02 109.22 0)
			(effects
				(font
					(size 1.27 1.27)
					(thickness 0.15)
				)
				(justify left bottom)
				(hide yes)
			)
		)
		(property "Author" "Antmicro"
			(at 162.56 109.22 0)
			(effects
				(font
					(size 1.27 1.27)
					(thickness 0.15)
				)
				(justify left bottom)
				(hide yes)
			)
		)
		(property "Val" "1u"
			(at 132.08 127 90)
			(effects
				(font
					(size 1.27 1.27)
					(thickness 0.15)
				)
				(justify right)
			)
		)
		(property "Voltage" "25V"
			(at 132.08 129.54 90)
			(effects
				(font
					(size 1.27 1.27)
				)
				(justify right)
				(hide yes)
			)
		)
		(property "Dielectric" "X5R"
			(at 167.64 109.22 0)
			(effects
				(font
					(size 1.27 1.27)
				)
				(justify left bottom)
				(hide yes)
			)
		)
		(pin "1"
		)
		(pin "2"
		)
		(instances
			(project "cm4-baseboard"
				(path ""
					(reference "C301")
					(unit 1)
				)
			)
		)
	)
	(symbol
		(lib_id "antmicropower:GND")
		(at 334.01 194.31 0)
		(unit 1)
		(exclude_from_sim no)
		(in_bom yes)
		(on_board yes)
		(dnp no)
		(fields_autoplaced yes)
		(property "Reference" "#PWR0330"
			(at 342.9 196.85 0)
			(effects
				(font
					(size 1.27 1.27)
					(thickness 0.15)
				)
				(justify left bottom)
				(hide yes)
			)
		)
		(property "Value" "GND"
			(at 331.9998 199.39 0)
			(effects
				(font
					(size 1.27 1.27)
					(thickness 0.15)
				)
				(justify left bottom)
			)
		)
		(property "Footprint" ""
			(at 342.9 201.93 0)
			(effects
				(font
					(size 1.27 1.27)
					(thickness 0.15)
				)
				(justify left bottom)
				(hide yes)
			)
		)
		(property "Datasheet" ""
			(at 342.9 207.01 0)
			(effects
				(font
					(size 1.27 1.27)
					(thickness 0.15)
				)
				(justify left bottom)
				(hide yes)
			)
		)
		(property "Description" ""
			(at 334.01 194.31 0)
			(effects
				(font
					(size 1.27 1.27)
				)
				(hide yes)
			)
		)
		(property "Author" "Antmicro"
			(at 342.9 201.93 0)
			(effects
				(font
					(size 1.27 1.27)
					(thickness 0.15)
				)
				(justify left bottom)
				(hide yes)
			)
		)
		(property "License" "Apache-2.0"
			(at 342.9 204.47 0)
			(effects
				(font
					(size 1.27 1.27)
					(thickness 0.15)
				)
				(justify left bottom)
				(hide yes)
			)
		)
		(pin "1"
		)
		(instances
			(project "cm4-baseboard"
				(path ""
					(reference "#PWR0330")
					(unit 1)
				)
			)
		)
	)
	(symbol
		(lib_id "antmicroTestPoints:TP_0.75mm_SMD")
		(at 109.22 120.65 90)
		(unit 1)
		(exclude_from_sim no)
		(in_bom no)
		(on_board yes)
		(dnp no)
		(fields_autoplaced yes)
		(property "Reference" "TP310"
			(at 111.125 117.4749 90)
			(effects
				(font
					(size 1.27 1.27)
				)
				(justify right)
			)
		)
		(property "Value" "TP_0.75mm_SMD"
			(at 111.76 120.65 0)
			(effects
				(font
					(size 1.27 1.27)
					(thickness 0.15)
				)
				(justify left bottom)
				(hide yes)
			)
		)
		(property "Footprint" "antmicro-footprints:TP_SMD_0.75mm"
			(at 104.14 115.57 0)
			(effects
				(font
					(size 1.27 1.27)
					(thickness 0.15)
				)
				(justify left bottom)
				(hide yes)
			)
		)
		(property "Datasheet" ""
			(at 101.6 115.57 0)
			(effects
				(font
					(size 1.27 1.27)
					(thickness 0.15)
				)
				(justify left bottom)
				(hide yes)
			)
		)
		(property "Description" ""
			(at 109.22 120.65 0)
			(effects
				(font
					(size 1.27 1.27)
				)
				(hide yes)
			)
		)
		(property "MPN" ""
			(at 109.22 120.65 0)
			(effects
				(font
					(size 1.27 1.27)
					(thickness 0.15)
				)
				(justify left bottom)
				(hide yes)
			)
		)
		(property "Manufacturer" ""
			(at 109.22 120.65 0)
			(effects
				(font
					(size 1.27 1.27)
					(thickness 0.15)
				)
				(justify left bottom)
				(hide yes)
			)
		)
		(property "Author" "Antmicro"
			(at 124.46 105.41 0)
			(effects
				(font
					(size 1.27 1.27)
					(thickness 0.15)
				)
				(justify left bottom)
				(hide yes)
			)
		)
		(property "License" "Apache-2.0"
			(at 127 105.41 0)
			(effects
				(font
					(size 1.27 1.27)
					(thickness 0.15)
				)
				(justify left bottom)
				(hide yes)
			)
		)
		(pin "1"
		)
		(instances
			(project "cm4-baseboard"
				(path ""
					(reference "TP310")
					(unit 1)
				)
			)
		)
	)
	(symbol
		(lib_id "antmicropower:VCC")
		(at 256.54 107.95 0)
		(unit 1)
		(exclude_from_sim no)
		(in_bom yes)
		(on_board yes)
		(dnp no)
		(fields_autoplaced yes)
		(property "Reference" "#PWR0314"
			(at 256.54 111.76 0)
			(effects
				(font
					(size 1.27 1.27)
				)
				(justify left bottom)
				(hide yes)
			)
		)
		(property "Value" "VCC"
			(at 256.54 102.87 0)
			(effects
				(font
					(size 1.27 1.27)
				)
			)
		)
		(property "Footprint" ""
			(at 256.54 107.95 0)
			(effects
				(font
					(size 1.27 1.27)
				)
				(justify left bottom)
				(hide yes)
			)
		)
		(property "Datasheet" ""
			(at 256.54 107.95 0)
			(effects
				(font
					(size 1.27 1.27)
				)
				(justify left bottom)
				(hide yes)
			)
		)
		(property "Description" ""
			(at 256.54 107.95 0)
			(effects
				(font
					(size 1.27 1.27)
				)
				(hide yes)
			)
		)
		(pin "1"
		)
		(instances
			(project "cm4-baseboard"
				(path ""
					(reference "#PWR0314")
					(unit 1)
				)
			)
		)
	)
	(symbol
		(lib_id "antmicroCapacitors0402:C_100n_0402")
		(at 318.77 226.06 180)
		(unit 1)
		(exclude_from_sim no)
		(in_bom yes)
		(on_board yes)
		(dnp no)
		(property "Reference" "C309"
			(at 316.23 223.52 0)
			(effects
				(font
					(size 1.27 1.27)
					(thickness 0.15)
				)
			)
		)
		(property "Value" "C_100n_0402"
			(at 298.45 215.9 0)
			(effects
				(font
					(size 1.27 1.27)
					(thickness 0.15)
				)
				(justify left bottom)
				(hide yes)
			)
		)
		(property "Footprint" "antmicro-footprints:C_0402_1005Metric"
			(at 298.45 213.36 0)
			(effects
				(font
					(size 1.27 1.27)
					(thickness 0.15)
				)
				(justify left bottom)
				(hide yes)
			)
		)
		(property "Datasheet" "https://www.murata.com/products/productdetail?partno=GRM155R61H104KE14%23"
			(at 298.45 210.82 0)
			(effects
				(font
					(size 1.27 1.27)
					(thickness 0.15)
				)
				(justify left bottom)
				(hide yes)
			)
		)
		(property "Description" ""
			(at 318.77 226.06 0)
			(effects
				(font
					(size 1.27 1.27)
				)
				(hide yes)
			)
		)
		(property "Manufacturer" "Murata"
			(at 298.45 205.74 0)
			(effects
				(font
					(size 1.27 1.27)
					(thickness 0.15)
				)
				(justify left bottom)
				(hide yes)
			)
		)
		(property "MPN" "GRM155R61H104KE14D"
			(at 298.45 208.28 0)
			(effects
				(font
					(size 1.27 1.27)
					(thickness 0.15)
				)
				(justify left bottom)
				(hide yes)
			)
		)
		(property "Val" "100n"
			(at 316.23 228.6 0)
			(effects
				(font
					(size 1.27 1.27)
					(thickness 0.15)
				)
			)
		)
		(property "License" "Apache-2.0"
			(at 298.45 203.2 0)
			(effects
				(font
					(size 1.27 1.27)
					(thickness 0.15)
				)
				(justify left bottom)
				(hide yes)
			)
		)
		(property "Author" "Antmicro"
			(at 298.45 200.66 0)
			(effects
				(font
					(size 1.27 1.27)
					(thickness 0.15)
				)
				(justify left bottom)
				(hide yes)
			)
		)
		(property "Voltage" "50V"
			(at 298.45 198.12 0)
			(effects
				(font
					(size 1.27 1.27)
				)
				(justify left bottom)
				(hide yes)
			)
		)
		(property "Dielectric" "X5R"
			(at 298.45 195.58 0)
			(effects
				(font
					(size 1.27 1.27)
				)
				(justify left bottom)
				(hide yes)
			)
		)
		(pin "1"
		)
		(pin "2"
		)
		(instances
			(project "cm4-baseboard"
				(path ""
					(reference "C309")
					(unit 1)
				)
			)
		)
	)
	(symbol
		(lib_id "antmicropower:GND")
		(at 260.35 119.38 0)
		(unit 1)
		(exclude_from_sim no)
		(in_bom yes)
		(on_board yes)
		(dnp no)
		(property "Reference" "#PWR0315"
			(at 260.35 125.73 0)
			(effects
				(font
					(size 1.27 1.27)
				)
				(justify left bottom)
				(hide yes)
			)
		)
		(property "Value" "GND"
			(at 260.35 123.19 0)
			(effects
				(font
					(size 1.27 1.27)
				)
			)
		)
		(property "Footprint" ""
			(at 269.24 127 0)
			(effects
				(font
					(size 1.27 1.27)
					(thickness 0.15)
				)
				(justify left bottom)
				(hide yes)
			)
		)
		(property "Datasheet" ""
			(at 269.24 132.08 0)
			(effects
				(font
					(size 1.27 1.27)
					(thickness 0.15)
				)
				(justify left bottom)
				(hide yes)
			)
		)
		(property "Description" ""
			(at 260.35 119.38 0)
			(effects
				(font
					(size 1.27 1.27)
				)
				(hide yes)
			)
		)
		(property "Author" "Antmicro"
			(at 269.24 127 0)
			(effects
				(font
					(size 1.27 1.27)
					(thickness 0.15)
				)
				(justify left bottom)
				(hide yes)
			)
		)
		(property "License" "Apache-2.0"
			(at 269.24 129.54 0)
			(effects
				(font
					(size 1.27 1.27)
					(thickness 0.15)
				)
				(justify left bottom)
				(hide yes)
			)
		)
		(pin "1"
		)
		(instances
			(project "cm4-baseboard"
				(path ""
					(reference "#PWR0315")
					(unit 1)
				)
			)
		)
	)
	(symbol
		(lib_id "antmicropower:GND")
		(at 281.94 130.81 0)
		(unit 1)
		(exclude_from_sim no)
		(in_bom yes)
		(on_board yes)
		(dnp no)
		(property "Reference" "#PWR0323"
			(at 281.94 137.16 0)
			(effects
				(font
					(size 1.27 1.27)
				)
				(justify left bottom)
				(hide yes)
			)
		)
		(property "Value" "GND"
			(at 278.13 132.08 0)
			(effects
				(font
					(size 1.27 1.27)
				)
			)
		)
		(property "Footprint" ""
			(at 290.83 138.43 0)
			(effects
				(font
					(size 1.27 1.27)
					(thickness 0.15)
				)
				(justify left bottom)
				(hide yes)
			)
		)
		(property "Datasheet" ""
			(at 290.83 143.51 0)
			(effects
				(font
					(size 1.27 1.27)
					(thickness 0.15)
				)
				(justify left bottom)
				(hide yes)
			)
		)
		(property "Description" ""
			(at 281.94 130.81 0)
			(effects
				(font
					(size 1.27 1.27)
				)
				(hide yes)
			)
		)
		(property "Author" "Antmicro"
			(at 290.83 138.43 0)
			(effects
				(font
					(size 1.27 1.27)
					(thickness 0.15)
				)
				(justify left bottom)
				(hide yes)
			)
		)
		(property "License" "Apache-2.0"
			(at 290.83 140.97 0)
			(effects
				(font
					(size 1.27 1.27)
					(thickness 0.15)
				)
				(justify left bottom)
				(hide yes)
			)
		)
		(pin "1"
		)
		(instances
			(project "cm4-baseboard"
				(path ""
					(reference "#PWR0323")
					(unit 1)
				)
			)
		)
	)
	(symbol
		(lib_id "antmicroResistors0402:R_2k2_0402")
		(at 334.01 193.04 90)
		(unit 1)
		(exclude_from_sim no)
		(in_bom yes)
		(on_board yes)
		(dnp no)
		(fields_autoplaced yes)
		(property "Reference" "R319"
			(at 336.55 189.23 90)
			(effects
				(font
					(size 1.27 1.27)
					(thickness 0.15)
				)
				(justify right)
			)
		)
		(property "Value" "R_2k2_0402"
			(at 346.71 172.72 0)
			(effects
				(font
					(size 1.27 1.27)
					(thickness 0.15)
				)
				(justify left bottom)
				(hide yes)
			)
		)
		(property "Footprint" "antmicro-footprints:R_0402_1005Metric"
			(at 349.25 172.72 0)
			(effects
				(font
					(size 1.27 1.27)
					(thickness 0.15)
				)
				(justify left bottom)
				(hide yes)
			)
		)
		(property "Datasheet" "https://www.bourns.com/docs/product-datasheets/cr.pdf"
			(at 351.79 172.72 0)
			(effects
				(font
					(size 1.27 1.27)
					(thickness 0.15)
				)
				(justify left bottom)
				(hide yes)
			)
		)
		(property "Description" ""
			(at 334.01 193.04 0)
			(effects
				(font
					(size 1.27 1.27)
				)
				(hide yes)
			)
		)
		(property "MPN" "CR0402-FX-2201GLF"
			(at 354.33 172.72 0)
			(effects
				(font
					(size 1.27 1.27)
					(thickness 0.15)
				)
				(justify left bottom)
				(hide yes)
			)
		)
		(property "Manufacturer" "Bourns"
			(at 356.87 172.72 0)
			(effects
				(font
					(size 1.27 1.27)
					(thickness 0.15)
				)
				(justify left bottom)
				(hide yes)
			)
		)
		(property "License" "Apache-2.0"
			(at 359.41 172.72 0)
			(effects
				(font
					(size 1.27 1.27)
					(thickness 0.15)
				)
				(justify left bottom)
				(hide yes)
			)
		)
		(property "Author" "Antmicro"
			(at 361.95 172.72 0)
			(effects
				(font
					(size 1.27 1.27)
					(thickness 0.15)
				)
				(justify left bottom)
				(hide yes)
			)
		)
		(property "Val" "2k2"
			(at 336.55 191.77 90)
			(effects
				(font
					(size 1.27 1.27)
					(thickness 0.15)
				)
				(justify right)
			)
		)
		(property "Tolerance" "1%"
			(at 344.17 172.72 0)
			(effects
				(font
					(size 1.27 1.27)
				)
				(justify left bottom)
				(hide yes)
			)
		)
		(pin "2"
		)
		(pin "1"
		)
		(instances
			(project "cm4-baseboard"
				(path ""
					(reference "R319")
					(unit 1)
				)
			)
		)
	)
	(symbol
		(lib_id "antmicroTVSDiodes:SMF4L15A")
		(at 43.18 124.46 270)
		(unit 1)
		(exclude_from_sim no)
		(in_bom yes)
		(on_board yes)
		(dnp no)
		(fields_autoplaced yes)
		(property "Reference" "D301"
			(at 45.085 125.73 90)
			(effects
				(font
					(size 1.27 1.27)
				)
				(justify left)
			)
		)
		(property "Value" "SMF4L15A"
			(at 40.64 128.27 90)
			(effects
				(font
					(size 1.27 1.27)
					(thickness 0.15)
				)
				(justify right)
				(hide yes)
			)
		)
		(property "Footprint" "antmicro-footprints:SOD-123FL"
			(at 33.02 151.13 0)
			(effects
				(font
					(size 1.27 1.27)
					(thickness 0.15)
				)
				(justify left bottom)
				(hide yes)
			)
		)
		(property "Datasheet" "https://www.littelfuse.com/media?resourcetype=datasheets&itemid=d2ba8fab-1de3-4176-8530-f36ecb0b8799&filename=smf4l"
			(at 30.48 151.13 0)
			(effects
				(font
					(size 1.27 1.27)
					(thickness 0.15)
				)
				(justify left bottom)
				(hide yes)
			)
		)
		(property "Description" ""
			(at 43.18 124.46 0)
			(effects
				(font
					(size 1.27 1.27)
				)
				(hide yes)
			)
		)
		(property "Manufacturer" "Littelfuse"
			(at 25.4 151.13 0)
			(effects
				(font
					(size 1.27 1.27)
					(thickness 0.15)
				)
				(justify left bottom)
				(hide yes)
			)
		)
		(property "MPN" "SMF4L15A"
			(at 45.085 128.27 90)
			(effects
				(font
					(size 1.27 1.27)
					(thickness 0.15)
				)
				(justify left)
			)
		)
		(property "Author" "Antmicro"
			(at 22.86 151.13 0)
			(effects
				(font
					(size 1.27 1.27)
					(thickness 0.15)
				)
				(justify left bottom)
				(hide yes)
			)
		)
		(property "License" "Apache-2.0"
			(at 20.32 151.13 0)
			(effects
				(font
					(size 1.27 1.27)
					(thickness 0.15)
				)
				(justify left bottom)
				(hide yes)
			)
		)
		(pin "1"
		)
		(pin "2"
		)
		(instances
			(project "cm4-baseboard"
				(path ""
					(reference "D301")
					(unit 1)
				)
			)
		)
	)
	(symbol
		(lib_id "antmicroResistors0402:R_2k2_0402")
		(at 334.01 237.49 90)
		(unit 1)
		(exclude_from_sim no)
		(in_bom yes)
		(on_board yes)
		(dnp no)
		(fields_autoplaced yes)
		(property "Reference" "R321"
			(at 336.55 233.68 90)
			(effects
				(font
					(size 1.27 1.27)
					(thickness 0.15)
				)
				(justify right)
			)
		)
		(property "Value" "R_2k2_0402"
			(at 346.71 217.17 0)
			(effects
				(font
					(size 1.27 1.27)
					(thickness 0.15)
				)
				(justify left bottom)
				(hide yes)
			)
		)
		(property "Footprint" "antmicro-footprints:R_0402_1005Metric"
			(at 349.25 217.17 0)
			(effects
				(font
					(size 1.27 1.27)
					(thickness 0.15)
				)
				(justify left bottom)
				(hide yes)
			)
		)
		(property "Datasheet" "https://www.bourns.com/docs/product-datasheets/cr.pdf"
			(at 351.79 217.17 0)
			(effects
				(font
					(size 1.27 1.27)
					(thickness 0.15)
				)
				(justify left bottom)
				(hide yes)
			)
		)
		(property "Description" ""
			(at 334.01 237.49 0)
			(effects
				(font
					(size 1.27 1.27)
				)
				(hide yes)
			)
		)
		(property "MPN" "CR0402-FX-2201GLF"
			(at 354.33 217.17 0)
			(effects
				(font
					(size 1.27 1.27)
					(thickness 0.15)
				)
				(justify left bottom)
				(hide yes)
			)
		)
		(property "Manufacturer" "Bourns"
			(at 356.87 217.17 0)
			(effects
				(font
					(size 1.27 1.27)
					(thickness 0.15)
				)
				(justify left bottom)
				(hide yes)
			)
		)
		(property "License" "Apache-2.0"
			(at 359.41 217.17 0)
			(effects
				(font
					(size 1.27 1.27)
					(thickness 0.15)
				)
				(justify left bottom)
				(hide yes)
			)
		)
		(property "Author" "Antmicro"
			(at 361.95 217.17 0)
			(effects
				(font
					(size 1.27 1.27)
					(thickness 0.15)
				)
				(justify left bottom)
				(hide yes)
			)
		)
		(property "Val" "2k2"
			(at 336.55 236.22 90)
			(effects
				(font
					(size 1.27 1.27)
					(thickness 0.15)
				)
				(justify right)
			)
		)
		(property "Tolerance" "1%"
			(at 344.17 217.17 0)
			(effects
				(font
					(size 1.27 1.27)
				)
				(justify left bottom)
				(hide yes)
			)
		)
		(pin "2"
		)
		(pin "1"
		)
		(instances
			(project "cm4-baseboard"
				(path ""
					(reference "R321")
					(unit 1)
				)
			)
		)
	)
	(symbol
		(lib_id "antmicroResistors0402:R_10k_0402")
		(at 279.4 232.41 270)
		(mirror x)
		(unit 1)
		(exclude_from_sim no)
		(in_bom yes)
		(on_board yes)
		(dnp no)
		(property "Reference" "R312"
			(at 278.13 229.87 90)
			(effects
				(font
					(size 1.27 1.27)
					(thickness 0.15)
				)
				(justify right top)
			)
		)
		(property "Value" "R_10k_0402"
			(at 266.7 212.09 0)
			(effects
				(font
					(size 1.27 1.27)
					(thickness 0.15)
				)
				(justify left bottom)
				(hide yes)
			)
		)
		(property "Footprint" "antmicro-footprints:R_0402_1005Metric"
			(at 264.16 212.09 0)
			(effects
				(font
					(size 1.27 1.27)
					(thickness 0.15)
				)
				(justify left bottom)
				(hide yes)
			)
		)
		(property "Datasheet" "https://www.bourns.com/docs/product-datasheets/cr.pdf"
			(at 261.62 212.09 0)
			(effects
				(font
					(size 1.27 1.27)
					(thickness 0.15)
				)
				(justify left bottom)
				(hide yes)
			)
		)
		(property "Description" ""
			(at 279.4 232.41 0)
			(effects
				(font
					(size 1.27 1.27)
				)
				(hide yes)
			)
		)
		(property "Manufacturer" "Bourns"
			(at 256.54 212.09 0)
			(effects
				(font
					(size 1.27 1.27)
					(thickness 0.15)
				)
				(justify left bottom)
				(hide yes)
			)
		)
		(property "MPN" "CR0402-FX-1002GLF"
			(at 259.08 212.09 0)
			(effects
				(font
					(size 1.27 1.27)
					(thickness 0.15)
				)
				(justify left bottom)
				(hide yes)
			)
		)
		(property "Val" "10k"
			(at 278.13 231.14 90)
			(effects
				(font
					(size 1.27 1.27)
					(thickness 0.15)
				)
				(justify right bottom)
			)
		)
		(property "License" "Apache-2.0"
			(at 254 212.09 0)
			(effects
				(font
					(size 1.27 1.27)
					(thickness 0.15)
				)
				(justify left bottom)
				(hide yes)
			)
		)
		(property "Author" "Antmicro"
			(at 251.46 212.09 0)
			(effects
				(font
					(size 1.27 1.27)
					(thickness 0.15)
				)
				(justify left bottom)
				(hide yes)
			)
		)
		(property "Tolerance" "1%"
			(at 269.24 212.09 0)
			(effects
				(font
					(size 1.27 1.27)
				)
				(justify left bottom)
				(hide yes)
			)
		)
		(pin "1"
		)
		(pin "2"
		)
		(instances
			(project "cm4-baseboard"
				(path ""
					(reference "R312")
					(unit 1)
				)
			)
		)
	)
	(symbol
		(lib_id "antmicropower:GND")
		(at 87.63 194.31 0)
		(unit 1)
		(exclude_from_sim no)
		(in_bom yes)
		(on_board yes)
		(dnp no)
		(property "Reference" "#PWR0307"
			(at 87.63 200.66 0)
			(effects
				(font
					(size 1.27 1.27)
				)
				(justify left bottom)
				(hide yes)
			)
		)
		(property "Value" "GND"
			(at 89.535 198.12 0)
			(effects
				(font
					(size 1.27 1.27)
				)
				(justify right)
			)
		)
		(property "Footprint" ""
			(at 96.52 201.93 0)
			(effects
				(font
					(size 1.27 1.27)
					(thickness 0.15)
				)
				(justify left bottom)
				(hide yes)
			)
		)
		(property "Datasheet" ""
			(at 96.52 207.01 0)
			(effects
				(font
					(size 1.27 1.27)
					(thickness 0.15)
				)
				(justify left bottom)
				(hide yes)
			)
		)
		(property "Description" ""
			(at 87.63 194.31 0)
			(effects
				(font
					(size 1.27 1.27)
				)
				(hide yes)
			)
		)
		(property "Author" "Antmicro"
			(at 96.52 201.93 0)
			(effects
				(font
					(size 1.27 1.27)
					(thickness 0.15)
				)
				(justify left bottom)
				(hide yes)
			)
		)
		(property "License" "Apache-2.0"
			(at 96.52 204.47 0)
			(effects
				(font
					(size 1.27 1.27)
					(thickness 0.15)
				)
				(justify left bottom)
				(hide yes)
			)
		)
		(pin "1"
		)
		(instances
			(project "cm4-baseboard"
				(path ""
					(reference "#PWR0307")
					(unit 1)
				)
			)
		)
	)
	(symbol
		(lib_id "antmicroTestPoints:TP_0.75mm_SMD")
		(at 289.56 134.62 0)
		(mirror y)
		(unit 1)
		(exclude_from_sim no)
		(in_bom no)
		(on_board yes)
		(dnp no)
		(fields_autoplaced yes)
		(property "Reference" "TP304"
			(at 286.385 132.08 0)
			(effects
				(font
					(size 1.27 1.27)
					(thickness 0.15)
				)
			)
		)
		(property "Value" "TP_0.75mm_SMD"
			(at 274.32 142.24 0)
			(effects
				(font
					(size 1.27 1.27)
					(thickness 0.15)
				)
				(justify left bottom)
				(hide yes)
			)
		)
		(property "Footprint" "antmicro-footprints:TP_SMD_0.75mm"
			(at 278.765 140.97 0)
			(effects
				(font
					(size 1.27 1.27)
					(thickness 0.15)
				)
				(justify left bottom)
				(hide yes)
			)
		)
		(property "Datasheet" ""
			(at 271.78 147.32 0)
			(effects
				(font
					(size 1.27 1.27)
					(thickness 0.15)
				)
				(justify left bottom)
				(hide yes)
			)
		)
		(property "Description" ""
			(at 289.56 134.62 0)
			(effects
				(font
					(size 1.27 1.27)
				)
				(hide yes)
			)
		)
		(property "Author" "Antmicro"
			(at 278.765 143.51 0)
			(effects
				(font
					(size 1.27 1.27)
					(thickness 0.15)
				)
				(justify left bottom)
				(hide yes)
			)
		)
		(property "License" "Apache-2.0"
			(at 278.765 146.05 0)
			(effects
				(font
					(size 1.27 1.27)
					(thickness 0.15)
				)
				(justify left bottom)
				(hide yes)
			)
		)
		(property "MPN" ""
			(at 278.765 146.05 0)
			(effects
				(font
					(size 1.27 1.27)
					(thickness 0.15)
				)
				(justify left bottom)
				(hide yes)
			)
		)
		(property "Manufacturer" ""
			(at 278.765 140.97 0)
			(effects
				(font
					(size 1.27 1.27)
					(thickness 0.15)
				)
				(justify left bottom)
				(hide yes)
			)
		)
		(pin "1"
		)
		(instances
			(project "cm4-baseboard"
				(path ""
					(reference "TP304")
					(unit 1)
				)
			)
		)
	)
	(symbol
		(lib_id "antmicroDCDCConverters:AP62301_TSOT")
		(at 290.83 220.98 0)
		(unit 1)
		(exclude_from_sim no)
		(in_bom yes)
		(on_board yes)
		(dnp no)
		(fields_autoplaced yes)
		(property "Reference" "U302"
			(at 300.99 213.36 0)
			(effects
				(font
					(size 1.27 1.27)
					(thickness 0.15)
				)
			)
		)
		(property "Value" "AP62301_TSOT"
			(at 326.39 228.6 0)
			(effects
				(font
					(size 1.27 1.27)
					(thickness 0.15)
				)
				(justify left bottom)
				(hide yes)
			)
		)
		(property "Footprint" "antmicro-footprints:TSOT23-6"
			(at 326.39 231.14 0)
			(effects
				(font
					(size 1.27 1.27)
					(thickness 0.15)
				)
				(justify left bottom)
				(hide yes)
			)
		)
		(property "Datasheet" "https://www.diodes.com/assets/Datasheets/AP62300_AP62301_AP62300T.pdf"
			(at 326.39 233.68 0)
			(effects
				(font
					(size 1.27 1.27)
					(thickness 0.15)
				)
				(justify left bottom)
				(hide yes)
			)
		)
		(property "Description" ""
			(at 290.83 220.98 0)
			(effects
				(font
					(size 1.27 1.27)
				)
				(hide yes)
			)
		)
		(property "MPN" "AP62301WU-7"
			(at 300.99 215.9 0)
			(effects
				(font
					(size 1.27 1.27)
					(thickness 0.15)
				)
			)
		)
		(property "Manufacturer" "Diodes Incorporated"
			(at 326.39 236.22 0)
			(effects
				(font
					(size 1.27 1.27)
					(thickness 0.15)
				)
				(justify left bottom)
				(hide yes)
			)
		)
		(property "Author" "Antmicro"
			(at 326.39 238.76 0)
			(effects
				(font
					(size 1.27 1.27)
					(thickness 0.15)
				)
				(justify left bottom)
				(hide yes)
			)
		)
		(property "License" "Apache-2.0"
			(at 326.39 241.3 0)
			(effects
				(font
					(size 1.27 1.27)
					(thickness 0.15)
				)
				(justify left bottom)
				(hide yes)
			)
		)
		(pin "1"
		)
		(pin "2"
		)
		(pin "3"
		)
		(pin "4"
		)
		(pin "5"
		)
		(pin "6"
		)
		(instances
			(project "cm4-baseboard"
				(path ""
					(reference "U302")
					(unit 1)
				)
			)
		)
	)
	(symbol
		(lib_id "antmicroLEDIndicationDiscrete:LED_G_0603_KP-1608CGCK")
		(at 175.26 139.7 270)
		(mirror x)
		(unit 1)
		(exclude_from_sim no)
		(in_bom yes)
		(on_board yes)
		(dnp no)
		(property "Reference" "D302"
			(at 181.61 135.89 90)
			(effects
				(font
					(size 1.27 1.27)
					(thickness 0.15)
				)
			)
		)
		(property "Value" "LED_G_0603_KP-1608CGCK"
			(at 167.64 116.84 0)
			(effects
				(font
					(size 1.27 1.27)
					(thickness 0.15)
				)
				(justify left bottom)
				(hide yes)
			)
		)
		(property "Footprint" "antmicro-footprints:LED_0603_1608Metric_G"
			(at 165.1 116.84 0)
			(effects
				(font
					(size 1.27 1.27)
					(thickness 0.15)
				)
				(justify left bottom)
				(hide yes)
			)
		)
		(property "Datasheet" "http://www.kingbright.com/attachments/file/psearch//000/00/00/KP-1608CGCK(Ver.23B).pdf"
			(at 162.56 116.84 0)
			(effects
				(font
					(size 1.27 1.27)
					(thickness 0.15)
				)
				(justify left bottom)
				(hide yes)
			)
		)
		(property "Description" ""
			(at 175.26 139.7 0)
			(effects
				(font
					(size 1.27 1.27)
				)
				(hide yes)
			)
		)
		(property "MPN" "KP-1608CGCK"
			(at 160.02 116.84 0)
			(effects
				(font
					(size 1.27 1.27)
					(thickness 0.15)
				)
				(justify left bottom)
				(hide yes)
			)
		)
		(property "Manufacturer" "Kingbright"
			(at 157.48 116.84 0)
			(effects
				(font
					(size 1.27 1.27)
					(thickness 0.15)
				)
				(justify left bottom)
				(hide yes)
			)
		)
		(property "Color" "Green"
			(at 181.61 138.43 90)
			(effects
				(font
					(size 1.27 1.27)
				)
			)
		)
		(property "Author" "Antmicro"
			(at 154.94 116.84 0)
			(effects
				(font
					(size 1.27 1.27)
					(thickness 0.15)
				)
				(justify left bottom)
				(hide yes)
			)
		)
		(property "License" "Apache-2.0"
			(at 152.4 116.84 0)
			(effects
				(font
					(size 1.27 1.27)
					(thickness 0.15)
				)
				(justify left bottom)
				(hide yes)
			)
		)
		(pin "2"
		)
		(pin "1"
		)
		(instances
			(project "cm4-baseboard"
				(path ""
					(reference "D302")
					(unit 1)
				)
			)
		)
	)
	(symbol
		(lib_id "antmicroTestPoints:TP_0.75mm_SMD")
		(at 187.96 121.92 0)
		(unit 1)
		(exclude_from_sim no)
		(in_bom no)
		(on_board yes)
		(dnp no)
		(fields_autoplaced yes)
		(property "Reference" "TP301"
			(at 193.04 121.9199 0)
			(effects
				(font
					(size 1.27 1.27)
				)
				(justify left)
			)
		)
		(property "Value" "TP_0.75mm_SMD"
			(at 187.96 124.46 0)
			(effects
				(font
					(size 1.27 1.27)
				)
				(justify left bottom)
				(hide yes)
			)
		)
		(property "Footprint" "antmicro-footprints:TP_SMD_0.75mm"
			(at 193.04 116.84 0)
			(effects
				(font
					(size 1.524 1.524)
				)
				(justify left bottom)
				(hide yes)
			)
		)
		(property "Datasheet" ""
			(at 193.04 114.3 0)
			(effects
				(font
					(size 1.524 1.524)
				)
				(justify left bottom)
				(hide yes)
			)
		)
		(property "Description" ""
			(at 187.96 121.92 0)
			(effects
				(font
					(size 1.27 1.27)
				)
				(hide yes)
			)
		)
		(property "MPN" ""
			(at 187.96 121.92 0)
			(effects
				(font
					(size 1.27 1.27)
				)
				(hide yes)
			)
		)
		(property "Manufacturer" ""
			(at 187.96 121.92 0)
			(effects
				(font
					(size 1.27 1.27)
				)
				(hide yes)
			)
		)
		(property "Author" "Antmicro"
			(at 203.2 137.16 0)
			(effects
				(font
					(size 1.27 1.27)
					(thickness 0.15)
				)
				(justify left bottom)
				(hide yes)
			)
		)
		(property "License" "Apache-2.0"
			(at 203.2 139.7 0)
			(effects
				(font
					(size 1.27 1.27)
					(thickness 0.15)
				)
				(justify left bottom)
				(hide yes)
			)
		)
		(pin "1"
		)
		(instances
			(project "cm4-baseboard"
				(path ""
					(reference "TP301")
					(unit 1)
				)
			)
		)
	)
	(symbol
		(lib_id "antmicroResistors0402:R_6k8_0402")
		(at 334.01 182.88 90)
		(unit 1)
		(exclude_from_sim no)
		(in_bom yes)
		(on_board yes)
		(dnp no)
		(fields_autoplaced yes)
		(property "Reference" "R318"
			(at 336.55 179.07 90)
			(effects
				(font
					(size 1.27 1.27)
					(thickness 0.15)
				)
				(justify right)
			)
		)
		(property "Value" "R_6k8_0402"
			(at 346.71 162.56 0)
			(effects
				(font
					(size 1.27 1.27)
					(thickness 0.15)
				)
				(justify left bottom)
				(hide yes)
			)
		)
		(property "Footprint" "antmicro-footprints:R_0402_1005Metric"
			(at 349.25 162.56 0)
			(effects
				(font
					(size 1.27 1.27)
					(thickness 0.15)
				)
				(justify left bottom)
				(hide yes)
			)
		)
		(property "Datasheet" "https://www.bourns.com/docs/product-datasheets/cr.pdf"
			(at 351.79 162.56 0)
			(effects
				(font
					(size 1.27 1.27)
					(thickness 0.15)
				)
				(justify left bottom)
				(hide yes)
			)
		)
		(property "Description" ""
			(at 334.01 182.88 0)
			(effects
				(font
					(size 1.27 1.27)
				)
				(hide yes)
			)
		)
		(property "MPN" "CR0402-FX-6801GLF"
			(at 354.33 162.56 0)
			(effects
				(font
					(size 1.27 1.27)
					(thickness 0.15)
				)
				(justify left bottom)
				(hide yes)
			)
		)
		(property "Manufacturer" "Bourns"
			(at 356.87 162.56 0)
			(effects
				(font
					(size 1.27 1.27)
					(thickness 0.15)
				)
				(justify left bottom)
				(hide yes)
			)
		)
		(property "License" "Apache-2.0"
			(at 359.41 162.56 0)
			(effects
				(font
					(size 1.27 1.27)
					(thickness 0.15)
				)
				(justify left bottom)
				(hide yes)
			)
		)
		(property "Author" "Antmicro"
			(at 361.95 162.56 0)
			(effects
				(font
					(size 1.27 1.27)
					(thickness 0.15)
				)
				(justify left bottom)
				(hide yes)
			)
		)
		(property "Val" "6k8"
			(at 336.55 181.61 90)
			(effects
				(font
					(size 1.27 1.27)
					(thickness 0.15)
				)
				(justify right)
			)
		)
		(property "Tolerance" "1%"
			(at 344.17 162.56 0)
			(effects
				(font
					(size 1.27 1.27)
				)
				(justify left bottom)
				(hide yes)
			)
		)
		(pin "2"
		)
		(pin "1"
		)
		(instances
			(project "cm4-baseboard"
				(path ""
					(reference "R318")
					(unit 1)
				)
			)
		)
	)
	(symbol
		(lib_id "antmicropower:GND")
		(at 355.6 194.31 0)
		(unit 1)
		(exclude_from_sim no)
		(in_bom yes)
		(on_board yes)
		(dnp no)
		(fields_autoplaced yes)
		(property "Reference" "#PWR0336"
			(at 364.49 196.85 0)
			(effects
				(font
					(size 1.27 1.27)
					(thickness 0.15)
				)
				(justify left bottom)
				(hide yes)
			)
		)
		(property "Value" "GND"
			(at 353.5898 199.39 0)
			(effects
				(font
					(size 1.27 1.27)
					(thickness 0.15)
				)
				(justify left bottom)
			)
		)
		(property "Footprint" ""
			(at 364.49 201.93 0)
			(effects
				(font
					(size 1.27 1.27)
					(thickness 0.15)
				)
				(justify left bottom)
				(hide yes)
			)
		)
		(property "Datasheet" ""
			(at 364.49 207.01 0)
			(effects
				(font
					(size 1.27 1.27)
					(thickness 0.15)
				)
				(justify left bottom)
				(hide yes)
			)
		)
		(property "Description" ""
			(at 355.6 194.31 0)
			(effects
				(font
					(size 1.27 1.27)
				)
				(hide yes)
			)
		)
		(property "Author" "Antmicro"
			(at 364.49 201.93 0)
			(effects
				(font
					(size 1.27 1.27)
					(thickness 0.15)
				)
				(justify left bottom)
				(hide yes)
			)
		)
		(property "License" "Apache-2.0"
			(at 364.49 204.47 0)
			(effects
				(font
					(size 1.27 1.27)
					(thickness 0.15)
				)
				(justify left bottom)
				(hide yes)
			)
		)
		(pin "1"
		)
		(instances
			(project "cm4-baseboard"
				(path ""
					(reference "#PWR0336")
					(unit 1)
				)
			)
		)
	)
	(symbol
		(lib_id "antmicropower:GND")
		(at 354.33 119.38 0)
		(unit 1)
		(exclude_from_sim no)
		(in_bom yes)
		(on_board yes)
		(dnp no)
		(property "Reference" "#PWR0335"
			(at 354.33 125.73 0)
			(effects
				(font
					(size 1.27 1.27)
				)
				(justify left bottom)
				(hide yes)
			)
		)
		(property "Value" "GND"
			(at 354.33 123.19 0)
			(effects
				(font
					(size 1.27 1.27)
				)
			)
		)
		(property "Footprint" ""
			(at 363.22 127 0)
			(effects
				(font
					(size 1.27 1.27)
					(thickness 0.15)
				)
				(justify left bottom)
				(hide yes)
			)
		)
		(property "Datasheet" ""
			(at 363.22 132.08 0)
			(effects
				(font
					(size 1.27 1.27)
					(thickness 0.15)
				)
				(justify left bottom)
				(hide yes)
			)
		)
		(property "Description" ""
			(at 354.33 119.38 0)
			(effects
				(font
					(size 1.27 1.27)
				)
				(hide yes)
			)
		)
		(property "Author" "Antmicro"
			(at 363.22 127 0)
			(effects
				(font
					(size 1.27 1.27)
					(thickness 0.15)
				)
				(justify left bottom)
				(hide yes)
			)
		)
		(property "License" "Apache-2.0"
			(at 363.22 129.54 0)
			(effects
				(font
					(size 1.27 1.27)
					(thickness 0.15)
				)
				(justify left bottom)
				(hide yes)
			)
		)
		(pin "1"
		)
		(instances
			(project "cm4-baseboard"
				(path ""
					(reference "#PWR0335")
					(unit 1)
				)
			)
		)
	)
	(symbol
		(lib_id "antmicropower:+3V3")
		(at 388.62 219.71 0)
		(unit 1)
		(exclude_from_sim no)
		(in_bom yes)
		(on_board yes)
		(dnp no)
		(fields_autoplaced yes)
		(property "Reference" "#PWR0344"
			(at 388.62 223.52 0)
			(effects
				(font
					(size 1.27 1.27)
				)
				(justify left bottom)
				(hide yes)
			)
		)
		(property "Value" "+3V3"
			(at 388.62 214.63 0)
			(effects
				(font
					(size 1.27 1.27)
				)
			)
		)
		(property "Footprint" ""
			(at 388.62 219.71 0)
			(effects
				(font
					(size 1.27 1.27)
				)
				(justify left bottom)
				(hide yes)
			)
		)
		(property "Datasheet" ""
			(at 388.62 219.71 0)
			(effects
				(font
					(size 1.27 1.27)
				)
				(justify left bottom)
				(hide yes)
			)
		)
		(property "Description" ""
			(at 388.62 219.71 0)
			(effects
				(font
					(size 1.27 1.27)
				)
				(hide yes)
			)
		)
		(property "Author" "Antmicro"
			(at 403.86 222.25 0)
			(effects
				(font
					(size 1.27 1.27)
					(thickness 0.15)
				)
				(justify left bottom)
				(hide yes)
			)
		)
		(property "License" "Apache-2.0"
			(at 403.86 224.79 0)
			(effects
				(font
					(size 1.27 1.27)
					(thickness 0.15)
				)
				(justify left bottom)
				(hide yes)
			)
		)
		(pin "1"
		)
		(instances
			(project "cm4-baseboard"
				(path ""
					(reference "#PWR0344")
					(unit 1)
				)
			)
		)
	)
	(symbol
		(lib_id "antmicropower:GND")
		(at 345.44 119.38 0)
		(unit 1)
		(exclude_from_sim no)
		(in_bom yes)
		(on_board yes)
		(dnp no)
		(property "Reference" "#PWR0332"
			(at 345.44 125.73 0)
			(effects
				(font
					(size 1.27 1.27)
				)
				(justify left bottom)
				(hide yes)
			)
		)
		(property "Value" "GND"
			(at 345.44 123.19 0)
			(effects
				(font
					(size 1.27 1.27)
				)
			)
		)
		(property "Footprint" ""
			(at 354.33 127 0)
			(effects
				(font
					(size 1.27 1.27)
					(thickness 0.15)
				)
				(justify left bottom)
				(hide yes)
			)
		)
		(property "Datasheet" ""
			(at 354.33 132.08 0)
			(effects
				(font
					(size 1.27 1.27)
					(thickness 0.15)
				)
				(justify left bottom)
				(hide yes)
			)
		)
		(property "Description" ""
			(at 345.44 119.38 0)
			(effects
				(font
					(size 1.27 1.27)
				)
				(hide yes)
			)
		)
		(property "Author" "Antmicro"
			(at 354.33 127 0)
			(effects
				(font
					(size 1.27 1.27)
					(thickness 0.15)
				)
				(justify left bottom)
				(hide yes)
			)
		)
		(property "License" "Apache-2.0"
			(at 354.33 129.54 0)
			(effects
				(font
					(size 1.27 1.27)
					(thickness 0.15)
				)
				(justify left bottom)
				(hide yes)
			)
		)
		(pin "1"
		)
		(instances
			(project "cm4-baseboard"
				(path ""
					(reference "#PWR0332")
					(unit 1)
				)
			)
		)
	)
	(symbol
		(lib_id "antmicropower:GND")
		(at 175.26 144.78 0)
		(mirror y)
		(unit 1)
		(exclude_from_sim no)
		(in_bom yes)
		(on_board yes)
		(dnp no)
		(fields_autoplaced yes)
		(property "Reference" "#PWR0310"
			(at 175.26 151.13 0)
			(effects
				(font
					(size 1.27 1.27)
				)
				(justify left bottom)
				(hide yes)
			)
		)
		(property "Value" "GND"
			(at 175.26 149.86 0)
			(effects
				(font
					(size 1.27 1.27)
				)
			)
		)
		(property "Footprint" ""
			(at 166.37 152.4 0)
			(effects
				(font
					(size 1.27 1.27)
					(thickness 0.15)
				)
				(justify left bottom)
				(hide yes)
			)
		)
		(property "Datasheet" ""
			(at 166.37 157.48 0)
			(effects
				(font
					(size 1.27 1.27)
					(thickness 0.15)
				)
				(justify left bottom)
				(hide yes)
			)
		)
		(property "Description" ""
			(at 175.26 144.78 0)
			(effects
				(font
					(size 1.27 1.27)
				)
				(hide yes)
			)
		)
		(property "Author" "Antmicro"
			(at 166.37 152.4 0)
			(effects
				(font
					(size 1.27 1.27)
					(thickness 0.15)
				)
				(justify left bottom)
				(hide yes)
			)
		)
		(property "License" "Apache-2.0"
			(at 166.37 154.94 0)
			(effects
				(font
					(size 1.27 1.27)
					(thickness 0.15)
				)
				(justify left bottom)
				(hide yes)
			)
		)
		(pin "1"
		)
		(instances
			(project "cm4-baseboard"
				(path ""
					(reference "#PWR0310")
					(unit 1)
				)
			)
		)
	)
	(symbol
		(lib_id "antmicropower:PWR_FLAG")
		(at 370.84 173.99 0)
		(unit 1)
		(exclude_from_sim no)
		(in_bom yes)
		(on_board yes)
		(dnp no)
		(property "Reference" "#FLG07"
			(at 370.84 172.085 0)
			(effects
				(font
					(size 1.27 1.27)
				)
				(hide yes)
			)
		)
		(property "Value" "PWR_FLAG"
			(at 373.38 170.18 0)
			(effects
				(font
					(size 1.27 1.27)
				)
			)
		)
		(property "Footprint" ""
			(at 370.84 173.99 0)
			(effects
				(font
					(size 1.27 1.27)
				)
				(hide yes)
			)
		)
		(property "Datasheet" ""
			(at 370.84 173.99 0)
			(effects
				(font
					(size 1.27 1.27)
				)
				(hide yes)
			)
		)
		(property "Description" ""
			(at 370.84 173.99 0)
			(effects
				(font
					(size 1.27 1.27)
				)
				(hide yes)
			)
		)
		(pin "1"
		)
		(instances
			(project "cm4-baseboard"
				(path ""
					(reference "#FLG07")
					(unit 1)
				)
			)
		)
	)
	(symbol
		(lib_id "antmicroResistors0402:R_4k7_0402")
		(at 124.46 129.54 90)
		(unit 1)
		(exclude_from_sim no)
		(in_bom yes)
		(on_board yes)
		(dnp no)
		(property "Reference" "R307"
			(at 125.73 125.73 90)
			(effects
				(font
					(size 1.27 1.27)
				)
				(justify right)
			)
		)
		(property "Value" "R_4k7_0402"
			(at 128.27 129.54 0)
			(effects
				(font
					(size 1.27 1.27)
				)
				(justify left bottom)
				(hide yes)
			)
		)
		(property "Footprint" "antmicro-footprints:R_0402_1005Metric"
			(at 119.38 124.46 0)
			(effects
				(font
					(size 1.524 1.524)
				)
				(justify left bottom)
				(hide yes)
			)
		)
		(property "Datasheet" "https://www.bourns.com/docs/product-datasheets/cr.pdf"
			(at 124.46 129.54 0)
			(effects
				(font
					(size 1.27 1.27)
				)
				(justify left bottom)
				(hide yes)
			)
		)
		(property "Description" ""
			(at 124.46 129.54 0)
			(effects
				(font
					(size 1.27 1.27)
				)
				(hide yes)
			)
		)
		(property "Manufacturer" "Bourns"
			(at 114.3 124.46 0)
			(effects
				(font
					(size 1.524 1.524)
				)
				(justify left bottom)
				(hide yes)
			)
		)
		(property "MPN" "CR0402-FX-4701GLF"
			(at 116.84 124.46 0)
			(effects
				(font
					(size 1.524 1.524)
				)
				(justify left bottom)
				(hide yes)
			)
		)
		(property "Val" "4k7"
			(at 125.73 128.27 90)
			(effects
				(font
					(size 1.27 1.27)
				)
				(justify right)
			)
		)
		(property "License" "Apache-2.0"
			(at 149.86 109.22 0)
			(effects
				(font
					(size 1.27 1.27)
					(thickness 0.15)
				)
				(justify left bottom)
				(hide yes)
			)
		)
		(property "Author" "Antmicro"
			(at 152.4 109.22 0)
			(effects
				(font
					(size 1.27 1.27)
					(thickness 0.15)
				)
				(justify left bottom)
				(hide yes)
			)
		)
		(property "Tolerance" "1%"
			(at 134.62 109.22 0)
			(effects
				(font
					(size 1.27 1.27)
				)
				(justify left bottom)
				(hide yes)
			)
		)
		(pin "1"
		)
		(pin "2"
		)
		(instances
			(project "cm4-baseboard"
				(path ""
					(reference "R307")
					(unit 1)
				)
			)
		)
	)
	(symbol
		(lib_id "antmicroResistors0402:R_470k_0402")
		(at 87.63 193.04 90)
		(unit 1)
		(exclude_from_sim no)
		(in_bom yes)
		(on_board yes)
		(dnp no)
		(property "Reference" "R305"
			(at 88.9 189.23 90)
			(effects
				(font
					(size 1.27 1.27)
					(thickness 0.15)
				)
				(justify right)
			)
		)
		(property "Value" "R_470k_0402"
			(at 100.33 172.72 0)
			(effects
				(font
					(size 1.27 1.27)
					(thickness 0.15)
				)
				(justify left bottom)
				(hide yes)
			)
		)
		(property "Footprint" "antmicro-footprints:R_0402_1005Metric"
			(at 102.87 172.72 0)
			(effects
				(font
					(size 1.27 1.27)
					(thickness 0.15)
				)
				(justify left bottom)
				(hide yes)
			)
		)
		(property "Datasheet" "https://www.bourns.com/docs/product-datasheets/cr.pdf"
			(at 105.41 172.72 0)
			(effects
				(font
					(size 1.27 1.27)
					(thickness 0.15)
				)
				(justify left bottom)
				(hide yes)
			)
		)
		(property "Description" ""
			(at 87.63 193.04 0)
			(effects
				(font
					(size 1.27 1.27)
				)
				(hide yes)
			)
		)
		(property "MPN" "CR0402-FX-4703GLF"
			(at 107.95 172.72 0)
			(effects
				(font
					(size 1.27 1.27)
					(thickness 0.15)
				)
				(justify left bottom)
				(hide yes)
			)
		)
		(property "Manufacturer" "Bourns"
			(at 110.49 172.72 0)
			(effects
				(font
					(size 1.27 1.27)
					(thickness 0.15)
				)
				(justify left bottom)
				(hide yes)
			)
		)
		(property "License" "Apache-2.0"
			(at 113.03 172.72 0)
			(effects
				(font
					(size 1.27 1.27)
					(thickness 0.15)
				)
				(justify left bottom)
				(hide yes)
			)
		)
		(property "Author" "Antmicro"
			(at 115.57 172.72 0)
			(effects
				(font
					(size 1.27 1.27)
					(thickness 0.15)
				)
				(justify left bottom)
				(hide yes)
			)
		)
		(property "Val" "470k"
			(at 88.9 191.77 90)
			(effects
				(font
					(size 1.27 1.27)
					(thickness 0.15)
				)
				(justify right)
			)
		)
		(property "Tolerance" "1%"
			(at 97.79 172.72 0)
			(effects
				(font
					(size 1.27 1.27)
				)
				(justify left bottom)
				(hide yes)
			)
		)
		(pin "1"
		)
		(pin "2"
		)
		(instances
			(project "cm4-baseboard"
				(path ""
					(reference "R305")
					(unit 1)
				)
			)
		)
	)
	(symbol
		(lib_id "antmicropower:VCC")
		(at 261.62 172.72 0)
		(unit 1)
		(exclude_from_sim no)
		(in_bom yes)
		(on_board yes)
		(dnp no)
		(fields_autoplaced yes)
		(property "Reference" "#PWR0316"
			(at 261.62 176.53 0)
			(effects
				(font
					(size 1.27 1.27)
				)
				(justify left bottom)
				(hide yes)
			)
		)
		(property "Value" "VCC"
			(at 261.62 167.64 0)
			(effects
				(font
					(size 1.27 1.27)
				)
			)
		)
		(property "Footprint" ""
			(at 261.62 172.72 0)
			(effects
				(font
					(size 1.27 1.27)
				)
				(justify left bottom)
				(hide yes)
			)
		)
		(property "Datasheet" ""
			(at 261.62 172.72 0)
			(effects
				(font
					(size 1.27 1.27)
				)
				(justify left bottom)
				(hide yes)
			)
		)
		(property "Description" ""
			(at 261.62 172.72 0)
			(effects
				(font
					(size 1.27 1.27)
				)
				(hide yes)
			)
		)
		(pin "1"
		)
		(instances
			(project "cm4-baseboard"
				(path ""
					(reference "#PWR0316")
					(unit 1)
				)
			)
		)
	)
	(symbol
		(lib_id "antmicroResistors0402:R_470R_0402")
		(at 388.62 227.33 270)
		(mirror x)
		(unit 1)
		(exclude_from_sim no)
		(in_bom yes)
		(on_board yes)
		(dnp no)
		(fields_autoplaced yes)
		(property "Reference" "R327"
			(at 391.16 223.5199 90)
			(effects
				(font
					(size 1.27 1.27)
				)
				(justify left)
			)
		)
		(property "Value" "R_470R_0402"
			(at 375.92 207.01 0)
			(effects
				(font
					(size 1.27 1.27)
					(thickness 0.15)
				)
				(justify left bottom)
				(hide yes)
			)
		)
		(property "Footprint" "antmicro-footprints:R_0402_1005Metric"
			(at 373.38 207.01 0)
			(effects
				(font
					(size 1.27 1.27)
					(thickness 0.15)
				)
				(justify left bottom)
				(hide yes)
			)
		)
		(property "Datasheet" "https://www.bourns.com/docs/product-datasheets/cr.pdf"
			(at 370.84 207.01 0)
			(effects
				(font
					(size 1.27 1.27)
					(thickness 0.15)
				)
				(justify left bottom)
				(hide yes)
			)
		)
		(property "Description" ""
			(at 388.62 227.33 0)
			(effects
				(font
					(size 1.27 1.27)
				)
				(hide yes)
			)
		)
		(property "Manufacturer" "Bourns"
			(at 365.76 207.01 0)
			(effects
				(font
					(size 1.27 1.27)
					(thickness 0.15)
				)
				(justify left bottom)
				(hide yes)
			)
		)
		(property "MPN" "CR0402-FX-4700GLF"
			(at 368.3 207.01 0)
			(effects
				(font
					(size 1.27 1.27)
					(thickness 0.15)
				)
				(justify left bottom)
				(hide yes)
			)
		)
		(property "Val" "470R"
			(at 391.16 226.0599 90)
			(effects
				(font
					(size 1.27 1.27)
					(thickness 0.15)
				)
				(justify left)
			)
		)
		(property "License" "Apache-2.0"
			(at 363.22 207.01 0)
			(effects
				(font
					(size 1.27 1.27)
					(thickness 0.15)
				)
				(justify left bottom)
				(hide yes)
			)
		)
		(property "Author" "Antmicro"
			(at 360.68 207.01 0)
			(effects
				(font
					(size 1.27 1.27)
					(thickness 0.15)
				)
				(justify left bottom)
				(hide yes)
			)
		)
		(property "Tolerance" "1%"
			(at 378.46 207.01 0)
			(effects
				(font
					(size 1.27 1.27)
				)
				(justify left bottom)
				(hide yes)
			)
		)
		(pin "1"
		)
		(pin "2"
		)
		(instances
			(project "cm4-baseboard"
				(path ""
					(reference "R327")
					(unit 1)
				)
			)
		)
	)
	(symbol
		(lib_id "antmicroCapacitorsmisc:C_22u_25V_0805")
		(at 345.44 113.03 90)
		(mirror x)
		(unit 1)
		(exclude_from_sim no)
		(in_bom yes)
		(on_board yes)
		(dnp no)
		(fields_autoplaced yes)
		(property "Reference" "C312"
			(at 342.9 113.0362 90)
			(effects
				(font
					(size 1.27 1.27)
				)
				(justify left)
			)
		)
		(property "Value" "C_22u_25V_0805"
			(at 349.25 113.03 0)
			(effects
				(font
					(size 1.27 1.27)
				)
				(justify left bottom)
				(hide yes)
			)
		)
		(property "Footprint" "antmicro-footprints:C_0805_2012Metric"
			(at 340.36 118.11 0)
			(effects
				(font
					(size 1.524 1.524)
				)
				(justify left bottom)
				(hide yes)
			)
		)
		(property "Datasheet" "https://product.samsungsem.com/mlcc/CL21A226MAYNNN.do"
			(at 345.44 113.03 0)
			(effects
				(font
					(size 1.27 1.27)
				)
				(justify left bottom)
				(hide yes)
			)
		)
		(property "Description" ""
			(at 345.44 113.03 0)
			(effects
				(font
					(size 1.27 1.27)
				)
				(hide yes)
			)
		)
		(property "Manufacturer" "Samsung Electro-Mechanics"
			(at 335.28 118.11 0)
			(effects
				(font
					(size 1.524 1.524)
				)
				(justify left bottom)
				(hide yes)
			)
		)
		(property "MPN" "CL21A226MAYNNNE"
			(at 337.82 118.11 0)
			(effects
				(font
					(size 1.524 1.524)
				)
				(justify left bottom)
				(hide yes)
			)
		)
		(property "Val" "22u"
			(at 342.9 115.5762 90)
			(effects
				(font
					(size 1.27 1.27)
				)
				(justify left)
			)
		)
		(property "License" "Apache-2.0"
			(at 368.3 133.35 0)
			(effects
				(font
					(size 1.27 1.27)
					(thickness 0.15)
				)
				(justify left bottom)
				(hide yes)
			)
		)
		(property "Author" "Antmicro"
			(at 370.84 133.35 0)
			(effects
				(font
					(size 1.27 1.27)
					(thickness 0.15)
				)
				(justify left bottom)
				(hide yes)
			)
		)
		(property "Voltage" "25V"
			(at 342.9 118.1162 90)
			(effects
				(font
					(size 1.27 1.27)
				)
				(justify left)
			)
		)
		(property "Dielectric" "X5R"
			(at 375.92 133.35 0)
			(effects
				(font
					(size 1.27 1.27)
				)
				(justify left bottom)
				(hide yes)
			)
		)
		(property "Public" "False"
			(at 378.46 133.35 0)
			(effects
				(font
					(size 1.27 1.27)
				)
				(justify left bottom)
				(hide yes)
			)
		)
		(pin "1"
		)
		(pin "2"
		)
		(instances
			(project "cm4-baseboard"
				(path ""
					(reference "C312")
					(unit 1)
				)
			)
		)
	)
	(symbol
		(lib_id "antmicropower:GND")
		(at 43.18 130.81 0)
		(mirror y)
		(unit 1)
		(exclude_from_sim no)
		(in_bom yes)
		(on_board yes)
		(dnp no)
		(fields_autoplaced yes)
		(property "Reference" "#PWR0302"
			(at 43.18 137.16 0)
			(effects
				(font
					(size 1.27 1.27)
				)
				(justify left bottom)
				(hide yes)
			)
		)
		(property "Value" "GND"
			(at 43.18 135.89 0)
			(effects
				(font
					(size 1.27 1.27)
				)
			)
		)
		(property "Footprint" ""
			(at 34.29 138.43 0)
			(effects
				(font
					(size 1.27 1.27)
					(thickness 0.15)
				)
				(justify left bottom)
				(hide yes)
			)
		)
		(property "Datasheet" ""
			(at 34.29 143.51 0)
			(effects
				(font
					(size 1.27 1.27)
					(thickness 0.15)
				)
				(justify left bottom)
				(hide yes)
			)
		)
		(property "Description" ""
			(at 43.18 130.81 0)
			(effects
				(font
					(size 1.27 1.27)
				)
				(hide yes)
			)
		)
		(property "Author" "Antmicro"
			(at 34.29 138.43 0)
			(effects
				(font
					(size 1.27 1.27)
					(thickness 0.15)
				)
				(justify left bottom)
				(hide yes)
			)
		)
		(property "License" "Apache-2.0"
			(at 34.29 140.97 0)
			(effects
				(font
					(size 1.27 1.27)
					(thickness 0.15)
				)
				(justify left bottom)
				(hide yes)
			)
		)
		(pin "1"
		)
		(instances
			(project "cm4-baseboard"
				(path ""
					(reference "#PWR0302")
					(unit 1)
				)
			)
		)
	)
	(symbol
		(lib_id "antmicroResistors0402:R_33k_0402")
		(at 281.94 118.11 90)
		(unit 1)
		(exclude_from_sim no)
		(in_bom yes)
		(on_board yes)
		(dnp no)
		(property "Reference" "R313"
			(at 283.21 114.3 90)
			(effects
				(font
					(size 1.27 1.27)
					(thickness 0.15)
				)
				(justify right)
			)
		)
		(property "Value" "R_33k_0402"
			(at 294.64 97.79 0)
			(effects
				(font
					(size 1.27 1.27)
					(thickness 0.15)
				)
				(justify left bottom)
				(hide yes)
			)
		)
		(property "Footprint" "antmicro-footprints:R_0402_1005Metric"
			(at 297.18 97.79 0)
			(effects
				(font
					(size 1.27 1.27)
					(thickness 0.15)
				)
				(justify left bottom)
				(hide yes)
			)
		)
		(property "Datasheet" "https://www.bourns.com/docs/product-datasheets/cr.pdf"
			(at 299.72 97.79 0)
			(effects
				(font
					(size 1.27 1.27)
					(thickness 0.15)
				)
				(justify left bottom)
				(hide yes)
			)
		)
		(property "Description" ""
			(at 281.94 118.11 0)
			(effects
				(font
					(size 1.27 1.27)
				)
				(hide yes)
			)
		)
		(property "MPN" "CR0402-FX-3302GLF"
			(at 302.26 97.79 0)
			(effects
				(font
					(size 1.27 1.27)
					(thickness 0.15)
				)
				(justify left bottom)
				(hide yes)
			)
		)
		(property "Manufacturer" "Bourns"
			(at 304.8 97.79 0)
			(effects
				(font
					(size 1.27 1.27)
					(thickness 0.15)
				)
				(justify left bottom)
				(hide yes)
			)
		)
		(property "License" "Apache-2.0"
			(at 307.34 97.79 0)
			(effects
				(font
					(size 1.27 1.27)
					(thickness 0.15)
				)
				(justify left bottom)
				(hide yes)
			)
		)
		(property "Author" "Antmicro"
			(at 309.88 97.79 0)
			(effects
				(font
					(size 1.27 1.27)
					(thickness 0.15)
				)
				(justify left bottom)
				(hide yes)
			)
		)
		(property "Val" "33k"
			(at 283.21 116.84 90)
			(effects
				(font
					(size 1.27 1.27)
					(thickness 0.15)
				)
				(justify right)
			)
		)
		(property "Tolerance" "1%"
			(at 292.1 97.79 0)
			(effects
				(font
					(size 1.27 1.27)
				)
				(justify left bottom)
				(hide yes)
			)
		)
		(pin "2"
		)
		(pin "1"
		)
		(instances
			(project "cm4-baseboard"
				(path ""
					(reference "R313")
					(unit 1)
				)
			)
		)
	)
	(symbol
		(lib_id "antmicropower:GND")
		(at 87.63 149.86 0)
		(unit 1)
		(exclude_from_sim no)
		(in_bom yes)
		(on_board yes)
		(dnp no)
		(property "Reference" "#PWR0306"
			(at 87.63 156.21 0)
			(effects
				(font
					(size 1.27 1.27)
				)
				(justify left bottom)
				(hide yes)
			)
		)
		(property "Value" "GND"
			(at 89.535 153.67 0)
			(effects
				(font
					(size 1.27 1.27)
				)
				(justify right)
			)
		)
		(property "Footprint" ""
			(at 96.52 157.48 0)
			(effects
				(font
					(size 1.27 1.27)
					(thickness 0.15)
				)
				(justify left bottom)
				(hide yes)
			)
		)
		(property "Datasheet" ""
			(at 96.52 162.56 0)
			(effects
				(font
					(size 1.27 1.27)
					(thickness 0.15)
				)
				(justify left bottom)
				(hide yes)
			)
		)
		(property "Description" ""
			(at 87.63 149.86 0)
			(effects
				(font
					(size 1.27 1.27)
				)
				(hide yes)
			)
		)
		(property "Author" "Antmicro"
			(at 96.52 157.48 0)
			(effects
				(font
					(size 1.27 1.27)
					(thickness 0.15)
				)
				(justify left bottom)
				(hide yes)
			)
		)
		(property "License" "Apache-2.0"
			(at 96.52 160.02 0)
			(effects
				(font
					(size 1.27 1.27)
					(thickness 0.15)
				)
				(justify left bottom)
				(hide yes)
			)
		)
		(pin "1"
		)
		(instances
			(project "cm4-baseboard"
				(path ""
					(reference "#PWR0306")
					(unit 1)
				)
			)
		)
	)
	(symbol
		(lib_id "antmicropower:GND")
		(at 318.77 137.16 0)
		(unit 1)
		(exclude_from_sim no)
		(in_bom yes)
		(on_board yes)
		(dnp no)
		(property "Reference" "#PWR0327"
			(at 318.77 143.51 0)
			(effects
				(font
					(size 1.27 1.27)
				)
				(justify left bottom)
				(hide yes)
			)
		)
		(property "Value" "GND"
			(at 317.5 140.97 0)
			(effects
				(font
					(size 1.27 1.27)
				)
			)
		)
		(property "Footprint" ""
			(at 327.66 144.78 0)
			(effects
				(font
					(size 1.27 1.27)
					(thickness 0.15)
				)
				(justify left bottom)
				(hide yes)
			)
		)
		(property "Datasheet" ""
			(at 327.66 149.86 0)
			(effects
				(font
					(size 1.27 1.27)
					(thickness 0.15)
				)
				(justify left bottom)
				(hide yes)
			)
		)
		(property "Description" ""
			(at 318.77 137.16 0)
			(effects
				(font
					(size 1.27 1.27)
				)
				(hide yes)
			)
		)
		(property "Author" "Antmicro"
			(at 327.66 144.78 0)
			(effects
				(font
					(size 1.27 1.27)
					(thickness 0.15)
				)
				(justify left bottom)
				(hide yes)
			)
		)
		(property "License" "Apache-2.0"
			(at 327.66 147.32 0)
			(effects
				(font
					(size 1.27 1.27)
					(thickness 0.15)
				)
				(justify left bottom)
				(hide yes)
			)
		)
		(pin "1"
		)
		(instances
			(project "cm4-baseboard"
				(path ""
					(reference "#PWR0327")
					(unit 1)
				)
			)
		)
	)
)
